(kicad_sch
	(version 20250114)
	(generator "eeschema")
	(generator_version "9.0")
	(paper "A3")
	(title_block
		(title "PolarFire SoM")
		(date "2025-07-22")
		(rev "1.1.4")
		(company "Antmicro Ltd")
		(comment 1 "www.antmicro.com")
	)
	(bus_alias "ULPI"
		(members "CLK" "DIR" "NXT" "STP" "DATA0" "DATA1" "DATA2" "DATA3" "DATA4"
			"DATA5" "DATA6" "DATA7" "RESET"
		)
	)
	(text "Truth table for PI3USB102G\n\nSEL | D+ | D-\n----------\n L  | D1+ | D1-\n H  | D2+ | D2-"
		(exclude_from_sim no)
		(at 252.73 190.5 0)
		(effects
			(font
				(size 1.27 1.27)
			)
			(justify left bottom)
			(href "https://www.diodes.com/assets/Datasheets/PI3USB102G.pdf#page=2")
		)
	)
	(text "USB OTG switching"
		(exclude_from_sim no)
		(at 275.59 138.43 0)
		(effects
			(font
				(size 2 2)
				(thickness 0.8)
				(bold yes)
			)
			(justify left bottom)
		)
	)
	(text "ULPI supply filtering"
		(exclude_from_sim no)
		(at 57.15 125.73 0)
		(effects
			(font
				(size 2 2)
				(thickness 0.8)
				(bold yes)
			)
			(justify left bottom)
		)
	)
	(text "USB PHY"
		(exclude_from_sim no)
		(at 15.24 21.59 0)
		(effects
			(font
				(size 4 4)
				(thickness 0.8)
				(bold yes)
			)
			(justify left bottom)
		)
	)
	(text "ULPI regulators inputs"
		(exclude_from_sim no)
		(at 100.33 125.73 0)
		(effects
			(font
				(size 2 2)
				(thickness 0.8)
				(bold yes)
			)
			(justify left bottom)
		)
	)
	(text "ULPI regulator output"
		(exclude_from_sim no)
		(at 142.875 125.73 0)
		(effects
			(font
				(size 2 2)
				(thickness 0.8)
				(bold yes)
			)
			(justify left bottom)
		)
	)
	(text "USB HUB"
		(exclude_from_sim no)
		(at 208.28 22.225 0)
		(effects
			(font
				(size 4 4)
				(thickness 0.8)
				(bold yes)
			)
			(justify left bottom)
		)
	)
	(text "REF CLK\n\n"
		(exclude_from_sim no)
		(at 185.42 254 0)
		(effects
			(font
				(size 4 4)
				(thickness 0.8)
				(bold yes)
			)
			(justify left bottom)
		)
	)
	(text "Logic Inverter"
		(exclude_from_sim no)
		(at 138.43 166.37 0)
		(effects
			(font
				(size 2 2)
				(thickness 0.8)
				(bold yes)
			)
			(justify left bottom)
		)
	)
	(text "USB_OTG_ID"
		(exclude_from_sim no)
		(at 67.31 166.37 0)
		(effects
			(font
				(size 2 2)
				(thickness 0.8)
				(bold yes)
			)
			(justify left bottom)
		)
	)
	(junction
		(at 140.97 76.2)
		(diameter 0)
		(color 0 0 0 0)
	)
	(junction
		(at 177.8 270.51)
		(diameter 0)
		(color 0 0 0 0)
	)
	(junction
		(at 139.7 195.58)
		(diameter 0)
		(color 0 0 0 0)
	)
	(junction
		(at 349.25 162.56)
		(diameter 0)
		(color 0 0 0 0)
	)
	(junction
		(at 73.66 133.35)
		(diameter 0)
		(color 0 0 0 0)
	)
	(junction
		(at 151.13 186.69)
		(diameter 0)
		(color 0 0 0 0)
	)
	(junction
		(at 186.69 264.16)
		(diameter 0)
		(color 0 0 0 0)
	)
	(junction
		(at 345.44 72.39)
		(diameter 0)
		(color 0 0 0 0)
	)
	(junction
		(at 151.13 177.8)
		(diameter 0)
		(color 0 0 0 0)
	)
	(junction
		(at 82.55 92.71)
		(diameter 0)
		(color 0 0 0 0)
	)
	(junction
		(at 322.58 105.41)
		(diameter 0)
		(color 0 0 0 0)
	)
	(junction
		(at 345.44 64.77)
		(diameter 0)
		(color 0 0 0 0)
	)
	(junction
		(at 177.8 262.89)
		(diameter 0)
		(color 0 0 0 0)
	)
	(junction
		(at 60.96 144.78)
		(diameter 0)
		(color 0 0 0 0)
	)
	(junction
		(at 354.33 72.39)
		(diameter 0)
		(color 0 0 0 0)
	)
	(junction
		(at 74.93 187.96)
		(diameter 0)
		(color 0 0 0 0)
	)
	(junction
		(at 271.78 55.88)
		(diameter 0)
		(color 0 0 0 0)
	)
	(junction
		(at 351.79 151.13)
		(diameter 0)
		(color 0 0 0 0)
	)
	(junction
		(at 60.96 133.35)
		(diameter 0)
		(color 0 0 0 0)
	)
	(junction
		(at 107.95 134.62)
		(diameter 0)
		(color 0 0 0 0)
	)
	(junction
		(at 125.73 134.62)
		(diameter 0)
		(color 0 0 0 0)
	)
	(junction
		(at 67.31 144.78)
		(diameter 0)
		(color 0 0 0 0)
	)
	(junction
		(at 346.71 153.67)
		(diameter 0)
		(color 0 0 0 0)
	)
	(junction
		(at 160.02 49.53)
		(diameter 0)
		(color 0 0 0 0)
	)
	(junction
		(at 354.33 64.77)
		(diameter 0)
		(color 0 0 0 0)
	)
	(junction
		(at 67.31 133.35)
		(diameter 0)
		(color 0 0 0 0)
	)
	(no_connect
		(at 309.88 64.77)
	)
	(no_connect
		(at 276.86 85.09)
	)
	(no_connect
		(at 309.88 62.23)
	)
	(no_connect
		(at 309.88 76.2)
	)
	(no_connect
		(at 276.86 91.44)
	)
	(no_connect
		(at 309.88 78.74)
	)
	(no_connect
		(at 276.86 88.9)
	)
	(bus_entry
		(at 358.14 148.59)
		(size -2.54 2.54)
		(stroke
			(width 0)
			(type default)
		)
	)
	(bus_entry
		(at 91.44 73.66)
		(size 2.54 2.54)
		(stroke
			(width 0)
			(type default)
		)
	)
	(bus_entry
		(at 91.44 71.12)
		(size 2.54 2.54)
		(stroke
			(width 0)
			(type default)
		)
	)
	(bus_entry
		(at 91.44 83.82)
		(size 2.54 2.54)
		(stroke
			(width 0)
			(type default)
		)
	)
	(bus_entry
		(at 69.85 90.17)
		(size 2.54 2.54)
		(stroke
			(width 0)
			(type default)
		)
	)
	(bus_entry
		(at 69.85 97.79)
		(size 2.54 2.54)
		(stroke
			(width 0)
			(type default)
		)
	)
	(bus_entry
		(at 119.38 193.04)
		(size 2.54 2.54)
		(stroke
			(width 0)
			(type default)
		)
	)
	(bus_entry
		(at 91.44 86.36)
		(size 2.54 2.54)
		(stroke
			(width 0)
			(type default)
		)
	)
	(bus_entry
		(at 91.44 78.74)
		(size 2.54 2.54)
		(stroke
			(width 0)
			(type default)
		)
	)
	(bus_entry
		(at 325.12 66.04)
		(size -2.54 2.54)
		(stroke
			(width 0)
			(type default)
		)
	)
	(bus_entry
		(at 69.85 92.71)
		(size 2.54 2.54)
		(stroke
			(width 0)
			(type default)
		)
	)
	(bus_entry
		(at 69.85 95.25)
		(size 2.54 2.54)
		(stroke
			(width 0)
			(type default)
		)
	)
	(bus_entry
		(at 325.12 68.58)
		(size -2.54 2.54)
		(stroke
			(width 0)
			(type default)
		)
	)
	(bus_entry
		(at 91.44 68.58)
		(size 2.54 2.54)
		(stroke
			(width 0)
			(type default)
		)
	)
	(bus_entry
		(at 91.44 81.28)
		(size 2.54 2.54)
		(stroke
			(width 0)
			(type default)
		)
	)
	(bus_entry
		(at 91.44 76.2)
		(size 2.54 2.54)
		(stroke
			(width 0)
			(type default)
		)
	)
	(bus_entry
		(at 358.14 151.13)
		(size -2.54 2.54)
		(stroke
			(width 0)
			(type default)
		)
	)
	(wire
		(pts
			(xy 133.35 100.33) (xy 133.35 102.87)
		)
		(stroke
			(width 0)
			(type default)
		)
	)
	(wire
		(pts
			(xy 351.79 162.56) (xy 349.25 162.56)
		)
		(stroke
			(width 0)
			(type default)
		)
	)
	(wire
		(pts
			(xy 142.24 95.25) (xy 147.32 95.25)
		)
		(stroke
			(width 0)
			(type default)
		)
	)
	(wire
		(pts
			(xy 74.93 177.8) (xy 74.93 180.34)
		)
		(stroke
			(width 0)
			(type default)
		)
	)
	(wire
		(pts
			(xy 160.02 41.91) (xy 160.02 43.18)
		)
		(stroke
			(width 0)
			(type default)
		)
	)
	(polyline
		(pts
			(xy 379.73 232.41) (xy 379.73 232.41)
		)
		(stroke
			(width 0)
			(type default)
		)
	)
	(wire
		(pts
			(xy 177.8 269.24) (xy 177.8 270.51)
		)
		(stroke
			(width 0)
			(type default)
		)
	)
	(bus
		(pts
			(xy 91.44 68.58) (xy 91.44 71.12)
		)
		(stroke
			(width 0)
			(type default)
		)
	)
	(bus
		(pts
			(xy 67.31 87.63) (xy 68.58 87.63)
		)
		(stroke
			(width 0)
			(type default)
		)
	)
	(wire
		(pts
			(xy 237.49 157.48) (xy 254 157.48)
		)
		(stroke
			(width 0)
			(type default)
		)
	)
	(bus
		(pts
			(xy 91.44 71.12) (xy 91.44 73.66)
		)
		(stroke
			(width 0)
			(type default)
		)
	)
	(bus
		(pts
			(xy 69.85 92.71) (xy 69.85 95.25)
		)
		(stroke
			(width 0)
			(type default)
		)
	)
	(wire
		(pts
			(xy 130.81 81.28) (xy 140.97 81.28)
		)
		(stroke
			(width 0)
			(type default)
		)
	)
	(wire
		(pts
			(xy 241.3 151.13) (xy 254 151.13)
		)
		(stroke
			(width 0)
			(type default)
		)
	)
	(wire
		(pts
			(xy 142.24 86.36) (xy 130.81 86.36)
		)
		(stroke
			(width 0)
			(type default)
		)
	)
	(wire
		(pts
			(xy 82.55 92.71) (xy 72.39 92.71)
		)
		(stroke
			(width 0)
			(type default)
		)
	)
	(bus
		(pts
			(xy 326.39 62.23) (xy 327.66 62.23)
		)
		(stroke
			(width 0)
			(type default)
		)
	)
	(wire
		(pts
			(xy 67.31 133.35) (xy 67.31 135.89)
		)
		(stroke
			(width 0)
			(type default)
		)
	)
	(bus
		(pts
			(xy 116.84 190.5) (xy 118.11 190.5)
		)
		(stroke
			(width 0)
			(type default)
		)
	)
	(wire
		(pts
			(xy 275.59 97.79) (xy 276.86 97.79)
		)
		(stroke
			(width 0)
			(type default)
		)
	)
	(wire
		(pts
			(xy 363.22 72.39) (xy 363.22 71.12)
		)
		(stroke
			(width 0)
			(type default)
		)
	)
	(wire
		(pts
			(xy 82.55 133.35) (xy 88.9 133.35)
		)
		(stroke
			(width 0)
			(type default)
		)
	)
	(wire
		(pts
			(xy 107.95 134.62) (xy 107.95 135.89)
		)
		(stroke
			(width 0)
			(type default)
		)
	)
	(bus
		(pts
			(xy 325.12 63.5) (xy 326.39 62.23)
		)
		(stroke
			(width 0)
			(type default)
		)
	)
	(wire
		(pts
			(xy 67.31 133.35) (xy 73.66 133.35)
		)
		(stroke
			(width 0)
			(type default)
		)
	)
	(wire
		(pts
			(xy 139.7 177.8) (xy 151.13 177.8)
		)
		(stroke
			(width 0)
			(type default)
		)
	)
	(bus
		(pts
			(xy 68.58 87.63) (xy 69.85 88.9)
		)
		(stroke
			(width 0)
			(type default)
		)
	)
	(wire
		(pts
			(xy 325.12 143.51) (xy 325.12 146.05)
		)
		(stroke
			(width 0)
			(type default)
		)
	)
	(wire
		(pts
			(xy 177.8 270.51) (xy 177.8 271.78)
		)
		(stroke
			(width 0)
			(type default)
		)
	)
	(wire
		(pts
			(xy 139.7 195.58) (xy 144.78 195.58)
		)
		(stroke
			(width 0)
			(type default)
		)
	)
	(wire
		(pts
			(xy 302.26 161.29) (xy 299.72 161.29)
		)
		(stroke
			(width 0)
			(type default)
		)
	)
	(wire
		(pts
			(xy 299.72 161.29) (xy 299.72 163.83)
		)
		(stroke
			(width 0)
			(type default)
		)
	)
	(bus
		(pts
			(xy 91.44 78.74) (xy 91.44 81.28)
		)
		(stroke
			(width 0)
			(type default)
		)
	)
	(wire
		(pts
			(xy 207.01 264.16) (xy 215.9 264.16)
		)
		(stroke
			(width 0)
			(type default)
		)
	)
	(wire
		(pts
			(xy 153.67 49.53) (xy 160.02 49.53)
		)
		(stroke
			(width 0)
			(type default)
		)
	)
	(wire
		(pts
			(xy 274.32 157.48) (xy 302.26 157.48)
		)
		(stroke
			(width 0)
			(type default)
		)
	)
	(wire
		(pts
			(xy 351.79 161.29) (xy 351.79 162.56)
		)
		(stroke
			(width 0)
			(type default)
		)
	)
	(wire
		(pts
			(xy 90.17 92.71) (xy 82.55 92.71)
		)
		(stroke
			(width 0)
			(type default)
		)
	)
	(wire
		(pts
			(xy 345.44 72.39) (xy 345.44 73.66)
		)
		(stroke
			(width 0)
			(type default)
		)
	)
	(wire
		(pts
			(xy 274.32 68.58) (xy 276.86 68.58)
		)
		(stroke
			(width 0)
			(type default)
		)
	)
	(wire
		(pts
			(xy 74.93 195.58) (xy 74.93 196.85)
		)
		(stroke
			(width 0)
			(type default)
		)
	)
	(wire
		(pts
			(xy 82.55 90.17) (xy 82.55 92.71)
		)
		(stroke
			(width 0)
			(type default)
		)
	)
	(wire
		(pts
			(xy 332.74 91.44) (xy 309.88 91.44)
		)
		(stroke
			(width 0)
			(type default)
		)
	)
	(bus
		(pts
			(xy 91.44 73.66) (xy 91.44 76.2)
		)
		(stroke
			(width 0)
			(type default)
		)
	)
	(wire
		(pts
			(xy 265.43 62.23) (xy 265.43 64.77)
		)
		(stroke
			(width 0)
			(type default)
		)
	)
	(wire
		(pts
			(xy 110.49 100.33) (xy 72.39 100.33)
		)
		(stroke
			(width 0)
			(type default)
		)
	)
	(polyline
		(pts
			(xy 201.93 231.14) (xy 406.4 231.14)
		)
		(stroke
			(width 0)
			(type dash)
		)
	)
	(wire
		(pts
			(xy 139.7 177.8) (xy 139.7 185.42)
		)
		(stroke
			(width 0)
			(type default)
		)
	)
	(wire
		(pts
			(xy 363.22 64.77) (xy 363.22 66.04)
		)
		(stroke
			(width 0)
			(type default)
		)
	)
	(wire
		(pts
			(xy 143.51 76.2) (xy 140.97 76.2)
		)
		(stroke
			(width 0)
			(type default)
		)
	)
	(wire
		(pts
			(xy 177.8 262.89) (xy 186.69 262.89)
		)
		(stroke
			(width 0)
			(type default)
		)
	)
	(wire
		(pts
			(xy 276.86 161.29) (xy 276.86 163.83)
		)
		(stroke
			(width 0)
			(type default)
		)
	)
	(wire
		(pts
			(xy 254 146.05) (xy 251.46 146.05)
		)
		(stroke
			(width 0)
			(type default)
		)
	)
	(wire
		(pts
			(xy 177.8 262.89) (xy 177.8 264.16)
		)
		(stroke
			(width 0)
			(type default)
		)
	)
	(wire
		(pts
			(xy 271.78 55.88) (xy 271.78 62.23)
		)
		(stroke
			(width 0)
			(type default)
		)
	)
	(bus
		(pts
			(xy 91.44 83.82) (xy 91.44 86.36)
		)
		(stroke
			(width 0)
			(type default)
		)
	)
	(wire
		(pts
			(xy 322.58 146.05) (xy 325.12 146.05)
		)
		(stroke
			(width 0)
			(type default)
		)
	)
	(wire
		(pts
			(xy 332.74 97.79) (xy 332.74 91.44)
		)
		(stroke
			(width 0)
			(type default)
		)
	)
	(wire
		(pts
			(xy 351.79 151.13) (xy 355.6 151.13)
		)
		(stroke
			(width 0)
			(type default)
		)
	)
	(wire
		(pts
			(xy 346.71 153.67) (xy 346.71 156.21)
		)
		(stroke
			(width 0)
			(type default)
		)
	)
	(bus
		(pts
			(xy 325.12 63.5) (xy 325.12 66.04)
		)
		(stroke
			(width 0)
			(type default)
		)
	)
	(wire
		(pts
			(xy 354.33 72.39) (xy 363.22 72.39)
		)
		(stroke
			(width 0)
			(type default)
		)
	)
	(wire
		(pts
			(xy 139.7 190.5) (xy 139.7 195.58)
		)
		(stroke
			(width 0)
			(type default)
		)
	)
	(wire
		(pts
			(xy 266.7 82.55) (xy 276.86 82.55)
		)
		(stroke
			(width 0)
			(type default)
		)
	)
	(wire
		(pts
			(xy 125.73 134.62) (xy 129.54 134.62)
		)
		(stroke
			(width 0)
			(type default)
		)
	)
	(polyline
		(pts
			(xy 12.065 231.14) (xy 201.93 231.14)
		)
		(stroke
			(width 0)
			(type dash)
		)
	)
	(wire
		(pts
			(xy 125.73 140.97) (xy 125.73 142.24)
		)
		(stroke
			(width 0)
			(type default)
		)
	)
	(wire
		(pts
			(xy 110.49 95.25) (xy 72.39 95.25)
		)
		(stroke
			(width 0)
			(type default)
		)
	)
	(wire
		(pts
			(xy 274.32 149.86) (xy 285.75 149.86)
		)
		(stroke
			(width 0)
			(type default)
		)
	)
	(wire
		(pts
			(xy 271.78 50.8) (xy 271.78 55.88)
		)
		(stroke
			(width 0)
			(type default)
		)
	)
	(wire
		(pts
			(xy 271.78 62.23) (xy 276.86 62.23)
		)
		(stroke
			(width 0)
			(type default)
		)
	)
	(wire
		(pts
			(xy 121.92 195.58) (xy 139.7 195.58)
		)
		(stroke
			(width 0)
			(type default)
		)
	)
	(wire
		(pts
			(xy 60.96 140.97) (xy 60.96 144.78)
		)
		(stroke
			(width 0)
			(type default)
		)
	)
	(bus
		(pts
			(xy 358.14 148.59) (xy 358.14 151.13)
		)
		(stroke
			(width 0)
			(type default)
		)
	)
	(wire
		(pts
			(xy 309.88 82.55) (xy 322.58 82.55)
		)
		(stroke
			(width 0)
			(type default)
		)
	)
	(wire
		(pts
			(xy 147.32 95.25) (xy 147.32 99.06)
		)
		(stroke
			(width 0)
			(type default)
		)
	)
	(wire
		(pts
			(xy 107.95 140.97) (xy 107.95 142.24)
		)
		(stroke
			(width 0)
			(type default)
		)
	)
	(wire
		(pts
			(xy 251.46 143.51) (xy 251.46 146.05)
		)
		(stroke
			(width 0)
			(type default)
		)
	)
	(wire
		(pts
			(xy 138.43 73.66) (xy 130.81 73.66)
		)
		(stroke
			(width 0)
			(type default)
		)
	)
	(wire
		(pts
			(xy 74.93 187.96) (xy 74.93 190.5)
		)
		(stroke
			(width 0)
			(type default)
		)
	)
	(wire
		(pts
			(xy 67.31 144.78) (xy 73.66 144.78)
		)
		(stroke
			(width 0)
			(type default)
		)
	)
	(wire
		(pts
			(xy 118.11 134.62) (xy 125.73 134.62)
		)
		(stroke
			(width 0)
			(type default)
		)
	)
	(wire
		(pts
			(xy 133.35 100.33) (xy 130.81 100.33)
		)
		(stroke
			(width 0)
			(type default)
		)
	)
	(wire
		(pts
			(xy 187.96 269.24) (xy 186.69 269.24)
		)
		(stroke
			(width 0)
			(type default)
		)
	)
	(wire
		(pts
			(xy 151.13 186.69) (xy 151.13 187.96)
		)
		(stroke
			(width 0)
			(type default)
		)
	)
	(wire
		(pts
			(xy 276.86 74.93) (xy 262.89 74.93)
		)
		(stroke
			(width 0)
			(type default)
		)
	)
	(wire
		(pts
			(xy 345.44 71.12) (xy 345.44 72.39)
		)
		(stroke
			(width 0)
			(type default)
		)
	)
	(wire
		(pts
			(xy 309.88 68.58) (xy 322.58 68.58)
		)
		(stroke
			(width 0)
			(type default)
		)
	)
	(wire
		(pts
			(xy 345.44 66.04) (xy 345.44 64.77)
		)
		(stroke
			(width 0)
			(type default)
		)
	)
	(wire
		(pts
			(xy 322.58 160.02) (xy 323.85 160.02)
		)
		(stroke
			(width 0)
			(type default)
		)
	)
	(wire
		(pts
			(xy 93.98 81.28) (xy 110.49 81.28)
		)
		(stroke
			(width 0)
			(type default)
		)
	)
	(wire
		(pts
			(xy 151.13 186.69) (xy 167.64 186.69)
		)
		(stroke
			(width 0)
			(type default)
		)
	)
	(wire
		(pts
			(xy 160.02 49.53) (xy 160.02 50.8)
		)
		(stroke
			(width 0)
			(type default)
		)
	)
	(wire
		(pts
			(xy 60.96 133.35) (xy 67.31 133.35)
		)
		(stroke
			(width 0)
			(type default)
		)
	)
	(wire
		(pts
			(xy 322.58 105.41) (xy 322.58 106.68)
		)
		(stroke
			(width 0)
			(type default)
		)
	)
	(wire
		(pts
			(xy 151.13 185.42) (xy 151.13 186.69)
		)
		(stroke
			(width 0)
			(type default)
		)
	)
	(bus
		(pts
			(xy 91.44 76.2) (xy 91.44 78.74)
		)
		(stroke
			(width 0)
			(type default)
		)
	)
	(wire
		(pts
			(xy 111.76 134.62) (xy 111.76 133.35)
		)
		(stroke
			(width 0)
			(type default)
		)
	)
	(wire
		(pts
			(xy 349.25 162.56) (xy 349.25 166.37)
		)
		(stroke
			(width 0)
			(type default)
		)
	)
	(wire
		(pts
			(xy 322.58 105.41) (xy 332.74 105.41)
		)
		(stroke
			(width 0)
			(type default)
		)
	)
	(wire
		(pts
			(xy 309.88 96.52) (xy 313.69 96.52)
		)
		(stroke
			(width 0)
			(type default)
		)
	)
	(wire
		(pts
			(xy 110.49 92.71) (xy 95.25 92.71)
		)
		(stroke
			(width 0)
			(type default)
		)
	)
	(wire
		(pts
			(xy 187.96 266.7) (xy 186.69 266.7)
		)
		(stroke
			(width 0)
			(type default)
		)
	)
	(bus
		(pts
			(xy 69.85 88.9) (xy 69.85 90.17)
		)
		(stroke
			(width 0)
			(type default)
		)
	)
	(wire
		(pts
			(xy 309.88 71.12) (xy 322.58 71.12)
		)
		(stroke
			(width 0)
			(type default)
		)
	)
	(wire
		(pts
			(xy 290.83 149.86) (xy 302.26 149.86)
		)
		(stroke
			(width 0)
			(type default)
		)
	)
	(wire
		(pts
			(xy 93.98 71.12) (xy 110.49 71.12)
		)
		(stroke
			(width 0)
			(type default)
		)
	)
	(wire
		(pts
			(xy 290.83 147.32) (xy 302.26 147.32)
		)
		(stroke
			(width 0)
			(type default)
		)
	)
	(wire
		(pts
			(xy 313.69 105.41) (xy 322.58 105.41)
		)
		(stroke
			(width 0)
			(type default)
		)
	)
	(wire
		(pts
			(xy 130.81 95.25) (xy 137.16 95.25)
		)
		(stroke
			(width 0)
			(type default)
		)
	)
	(wire
		(pts
			(xy 322.58 93.98) (xy 322.58 97.79)
		)
		(stroke
			(width 0)
			(type default)
		)
	)
	(wire
		(pts
			(xy 349.25 162.56) (xy 346.71 162.56)
		)
		(stroke
			(width 0)
			(type default)
		)
	)
	(bus
		(pts
			(xy 88.9 66.04) (xy 90.17 66.04)
		)
		(stroke
			(width 0)
			(type default)
		)
	)
	(bus
		(pts
			(xy 69.85 95.25) (xy 69.85 97.79)
		)
		(stroke
			(width 0)
			(type default)
		)
	)
	(wire
		(pts
			(xy 102.87 67.31) (xy 110.49 67.31)
		)
		(stroke
			(width 0)
			(type default)
		)
	)
	(wire
		(pts
			(xy 186.69 269.24) (xy 186.69 270.51)
		)
		(stroke
			(width 0)
			(type default)
		)
	)
	(bus
		(pts
			(xy 69.85 90.17) (xy 69.85 92.71)
		)
		(stroke
			(width 0)
			(type default)
		)
	)
	(wire
		(pts
			(xy 130.81 78.74) (xy 143.51 78.74)
		)
		(stroke
			(width 0)
			(type default)
		)
	)
	(bus
		(pts
			(xy 325.12 66.04) (xy 325.12 68.58)
		)
		(stroke
			(width 0)
			(type default)
		)
	)
	(wire
		(pts
			(xy 245.11 129.54) (xy 245.11 130.81)
		)
		(stroke
			(width 0)
			(type default)
		)
	)
	(wire
		(pts
			(xy 354.33 71.12) (xy 354.33 72.39)
		)
		(stroke
			(width 0)
			(type default)
		)
	)
	(wire
		(pts
			(xy 160.02 48.26) (xy 160.02 49.53)
		)
		(stroke
			(width 0)
			(type default)
		)
	)
	(wire
		(pts
			(xy 346.71 161.29) (xy 346.71 162.56)
		)
		(stroke
			(width 0)
			(type default)
		)
	)
	(bus
		(pts
			(xy 358.14 147.32) (xy 358.14 148.59)
		)
		(stroke
			(width 0)
			(type default)
		)
	)
	(wire
		(pts
			(xy 82.55 83.82) (xy 82.55 85.09)
		)
		(stroke
			(width 0)
			(type default)
		)
	)
	(wire
		(pts
			(xy 138.43 64.77) (xy 130.81 64.77)
		)
		(stroke
			(width 0)
			(type default)
		)
	)
	(wire
		(pts
			(xy 72.39 187.96) (xy 74.93 187.96)
		)
		(stroke
			(width 0)
			(type default)
		)
	)
	(bus
		(pts
			(xy 90.17 66.04) (xy 91.44 67.31)
		)
		(stroke
			(width 0)
			(type default)
		)
	)
	(wire
		(pts
			(xy 151.13 198.12) (xy 151.13 204.47)
		)
		(stroke
			(width 0)
			(type default)
		)
	)
	(bus
		(pts
			(xy 118.11 190.5) (xy 119.38 191.77)
		)
		(stroke
			(width 0)
			(type default)
		)
	)
	(wire
		(pts
			(xy 93.98 88.9) (xy 110.49 88.9)
		)
		(stroke
			(width 0)
			(type default)
		)
	)
	(wire
		(pts
			(xy 151.13 175.26) (xy 151.13 177.8)
		)
		(stroke
			(width 0)
			(type default)
		)
	)
	(wire
		(pts
			(xy 271.78 93.98) (xy 276.86 93.98)
		)
		(stroke
			(width 0)
			(type default)
		)
	)
	(wire
		(pts
			(xy 241.3 153.67) (xy 254 153.67)
		)
		(stroke
			(width 0)
			(type default)
		)
	)
	(wire
		(pts
			(xy 309.88 85.09) (xy 322.58 85.09)
		)
		(stroke
			(width 0)
			(type default)
		)
	)
	(wire
		(pts
			(xy 125.73 134.62) (xy 125.73 135.89)
		)
		(stroke
			(width 0)
			(type default)
		)
	)
	(wire
		(pts
			(xy 354.33 64.77) (xy 354.33 66.04)
		)
		(stroke
			(width 0)
			(type default)
		)
	)
	(wire
		(pts
			(xy 262.89 93.98) (xy 262.89 92.71)
		)
		(stroke
			(width 0)
			(type default)
		)
	)
	(wire
		(pts
			(xy 102.87 64.77) (xy 110.49 64.77)
		)
		(stroke
			(width 0)
			(type default)
		)
	)
	(wire
		(pts
			(xy 265.43 55.88) (xy 271.78 55.88)
		)
		(stroke
			(width 0)
			(type default)
		)
	)
	(wire
		(pts
			(xy 346.71 153.67) (xy 355.6 153.67)
		)
		(stroke
			(width 0)
			(type default)
		)
	)
	(wire
		(pts
			(xy 345.44 72.39) (xy 354.33 72.39)
		)
		(stroke
			(width 0)
			(type default)
		)
	)
	(wire
		(pts
			(xy 60.96 133.35) (xy 60.96 135.89)
		)
		(stroke
			(width 0)
			(type default)
		)
	)
	(wire
		(pts
			(xy 245.11 135.89) (xy 245.11 137.16)
		)
		(stroke
			(width 0)
			(type default)
		)
	)
	(wire
		(pts
			(xy 332.74 102.87) (xy 332.74 105.41)
		)
		(stroke
			(width 0)
			(type default)
		)
	)
	(wire
		(pts
			(xy 186.69 266.7) (xy 186.69 264.16)
		)
		(stroke
			(width 0)
			(type default)
		)
	)
	(wire
		(pts
			(xy 266.7 93.98) (xy 262.89 93.98)
		)
		(stroke
			(width 0)
			(type default)
		)
	)
	(wire
		(pts
			(xy 339.09 157.48) (xy 339.09 163.83)
		)
		(stroke
			(width 0)
			(type default)
		)
	)
	(wire
		(pts
			(xy 354.33 64.77) (xy 363.22 64.77)
		)
		(stroke
			(width 0)
			(type default)
		)
	)
	(wire
		(pts
			(xy 322.58 151.13) (xy 351.79 151.13)
		)
		(stroke
			(width 0)
			(type default)
		)
	)
	(bus
		(pts
			(xy 91.44 67.31) (xy 91.44 68.58)
		)
		(stroke
			(width 0)
			(type default)
		)
	)
	(wire
		(pts
			(xy 73.66 140.97) (xy 73.66 144.78)
		)
		(stroke
			(width 0)
			(type default)
		)
	)
	(wire
		(pts
			(xy 67.31 140.97) (xy 67.31 144.78)
		)
		(stroke
			(width 0)
			(type default)
		)
	)
	(wire
		(pts
			(xy 345.44 64.77) (xy 354.33 64.77)
		)
		(stroke
			(width 0)
			(type default)
		)
	)
	(wire
		(pts
			(xy 313.69 102.87) (xy 313.69 105.41)
		)
		(stroke
			(width 0)
			(type default)
		)
	)
	(wire
		(pts
			(xy 140.97 72.39) (xy 140.97 76.2)
		)
		(stroke
			(width 0)
			(type default)
		)
	)
	(wire
		(pts
			(xy 161.29 140.97) (xy 161.29 142.24)
		)
		(stroke
			(width 0)
			(type default)
		)
	)
	(wire
		(pts
			(xy 73.66 133.35) (xy 73.66 135.89)
		)
		(stroke
			(width 0)
			(type default)
		)
	)
	(wire
		(pts
			(xy 93.98 83.82) (xy 110.49 83.82)
		)
		(stroke
			(width 0)
			(type default)
		)
	)
	(wire
		(pts
			(xy 237.49 157.48) (xy 237.49 163.83)
		)
		(stroke
			(width 0)
			(type default)
		)
	)
	(wire
		(pts
			(xy 139.7 67.31) (xy 130.81 67.31)
		)
		(stroke
			(width 0)
			(type default)
		)
	)
	(wire
		(pts
			(xy 54.61 133.35) (xy 60.96 133.35)
		)
		(stroke
			(width 0)
			(type default)
		)
	)
	(wire
		(pts
			(xy 186.69 264.16) (xy 187.96 264.16)
		)
		(stroke
			(width 0)
			(type default)
		)
	)
	(wire
		(pts
			(xy 107.95 134.62) (xy 111.76 134.62)
		)
		(stroke
			(width 0)
			(type default)
		)
	)
	(wire
		(pts
			(xy 347.98 137.16) (xy 347.98 138.43)
		)
		(stroke
			(width 0)
			(type default)
		)
	)
	(wire
		(pts
			(xy 110.49 97.79) (xy 72.39 97.79)
		)
		(stroke
			(width 0)
			(type default)
		)
	)
	(wire
		(pts
			(xy 129.54 134.62) (xy 129.54 133.35)
		)
		(stroke
			(width 0)
			(type default)
		)
	)
	(wire
		(pts
			(xy 93.98 86.36) (xy 110.49 86.36)
		)
		(stroke
			(width 0)
			(type default)
		)
	)
	(wire
		(pts
			(xy 252.73 160.02) (xy 254 160.02)
		)
		(stroke
			(width 0)
			(type default)
		)
	)
	(wire
		(pts
			(xy 351.79 151.13) (xy 351.79 156.21)
		)
		(stroke
			(width 0)
			(type default)
		)
	)
	(wire
		(pts
			(xy 347.98 130.81) (xy 347.98 132.08)
		)
		(stroke
			(width 0)
			(type default)
		)
	)
	(wire
		(pts
			(xy 101.6 134.62) (xy 107.95 134.62)
		)
		(stroke
			(width 0)
			(type default)
		)
	)
	(wire
		(pts
			(xy 322.58 153.67) (xy 346.71 153.67)
		)
		(stroke
			(width 0)
			(type default)
		)
	)
	(bus
		(pts
			(xy 360.68 146.05) (xy 359.41 146.05)
		)
		(stroke
			(width 0)
			(type default)
		)
	)
	(wire
		(pts
			(xy 322.58 157.48) (xy 339.09 157.48)
		)
		(stroke
			(width 0)
			(type default)
		)
	)
	(wire
		(pts
			(xy 313.69 96.52) (xy 313.69 97.79)
		)
		(stroke
			(width 0)
			(type default)
		)
	)
	(wire
		(pts
			(xy 345.44 62.23) (xy 345.44 64.77)
		)
		(stroke
			(width 0)
			(type default)
		)
	)
	(wire
		(pts
			(xy 309.88 93.98) (xy 322.58 93.98)
		)
		(stroke
			(width 0)
			(type default)
		)
	)
	(wire
		(pts
			(xy 77.47 83.82) (xy 82.55 83.82)
		)
		(stroke
			(width 0)
			(type default)
		)
	)
	(wire
		(pts
			(xy 276.86 72.39) (xy 262.89 72.39)
		)
		(stroke
			(width 0)
			(type default)
		)
	)
	(wire
		(pts
			(xy 186.69 262.89) (xy 186.69 264.16)
		)
		(stroke
			(width 0)
			(type default)
		)
	)
	(wire
		(pts
			(xy 60.96 144.78) (xy 60.96 147.32)
		)
		(stroke
			(width 0)
			(type default)
		)
	)
	(wire
		(pts
			(xy 274.32 154.94) (xy 302.26 154.94)
		)
		(stroke
			(width 0)
			(type default)
		)
	)
	(wire
		(pts
			(xy 143.51 72.39) (xy 140.97 72.39)
		)
		(stroke
			(width 0)
			(type default)
		)
	)
	(wire
		(pts
			(xy 285.75 147.32) (xy 274.32 147.32)
		)
		(stroke
			(width 0)
			(type default)
		)
	)
	(wire
		(pts
			(xy 142.24 88.9) (xy 130.81 88.9)
		)
		(stroke
			(width 0)
			(type default)
		)
	)
	(wire
		(pts
			(xy 93.98 78.74) (xy 110.49 78.74)
		)
		(stroke
			(width 0)
			(type default)
		)
	)
	(wire
		(pts
			(xy 60.96 144.78) (xy 67.31 144.78)
		)
		(stroke
			(width 0)
			(type default)
		)
	)
	(wire
		(pts
			(xy 265.43 64.77) (xy 276.86 64.77)
		)
		(stroke
			(width 0)
			(type default)
		)
	)
	(wire
		(pts
			(xy 161.29 129.54) (xy 161.29 135.89)
		)
		(stroke
			(width 0)
			(type default)
		)
	)
	(wire
		(pts
			(xy 274.32 161.29) (xy 276.86 161.29)
		)
		(stroke
			(width 0)
			(type default)
		)
	)
	(wire
		(pts
			(xy 151.13 177.8) (xy 151.13 180.34)
		)
		(stroke
			(width 0)
			(type default)
		)
	)
	(wire
		(pts
			(xy 177.8 270.51) (xy 186.69 270.51)
		)
		(stroke
			(width 0)
			(type default)
		)
	)
	(wire
		(pts
			(xy 177.8 261.62) (xy 177.8 262.89)
		)
		(stroke
			(width 0)
			(type default)
		)
	)
	(wire
		(pts
			(xy 275.59 99.06) (xy 275.59 97.79)
		)
		(stroke
			(width 0)
			(type default)
		)
	)
	(wire
		(pts
			(xy 93.98 76.2) (xy 110.49 76.2)
		)
		(stroke
			(width 0)
			(type default)
		)
	)
	(wire
		(pts
			(xy 73.66 133.35) (xy 77.47 133.35)
		)
		(stroke
			(width 0)
			(type default)
		)
	)
	(wire
		(pts
			(xy 322.58 102.87) (xy 322.58 105.41)
		)
		(stroke
			(width 0)
			(type default)
		)
	)
	(bus
		(pts
			(xy 91.44 81.28) (xy 91.44 83.82)
		)
		(stroke
			(width 0)
			(type default)
		)
	)
	(wire
		(pts
			(xy 160.02 55.88) (xy 160.02 57.15)
		)
		(stroke
			(width 0)
			(type default)
		)
	)
	(bus
		(pts
			(xy 119.38 191.77) (xy 119.38 193.04)
		)
		(stroke
			(width 0)
			(type default)
		)
	)
	(polyline
		(pts
			(xy 201.295 230.505) (xy 201.295 12.7)
		)
		(stroke
			(width 0)
			(type dash)
		)
	)
	(wire
		(pts
			(xy 138.43 71.12) (xy 130.81 71.12)
		)
		(stroke
			(width 0)
			(type default)
		)
	)
	(wire
		(pts
			(xy 88.9 133.35) (xy 88.9 132.08)
		)
		(stroke
			(width 0)
			(type default)
		)
	)
	(bus
		(pts
			(xy 359.41 146.05) (xy 358.14 147.32)
		)
		(stroke
			(width 0)
			(type default)
		)
	)
	(wire
		(pts
			(xy 74.93 185.42) (xy 74.93 187.96)
		)
		(stroke
			(width 0)
			(type default)
		)
	)
	(wire
		(pts
			(xy 140.97 76.2) (xy 130.81 76.2)
		)
		(stroke
			(width 0)
			(type default)
		)
	)
	(wire
		(pts
			(xy 265.43 57.15) (xy 265.43 55.88)
		)
		(stroke
			(width 0)
			(type default)
		)
	)
	(wire
		(pts
			(xy 93.98 73.66) (xy 110.49 73.66)
		)
		(stroke
			(width 0)
			(type default)
		)
	)
	(label "ULPI.DATA4"
		(at 93.98 81.28 0)
		(effects
			(font
				(size 1.27 1.27)
			)
			(justify left bottom)
		)
	)
	(label "USB_P"
		(at 241.3 151.13 0)
		(effects
			(font
				(size 1.27 1.27)
			)
			(justify left bottom)
		)
	)
	(label "VDD33"
		(at 161.29 129.54 270)
		(effects
			(font
				(size 1.27 1.27)
			)
			(justify right bottom)
		)
	)
	(label "WL_BT.D_N"
		(at 310.515 71.12 0)
		(effects
			(font
				(size 1.27 1.27)
			)
			(justify left bottom)
		)
	)
	(label "RESETB"
		(at 142.24 88.9 180)
		(effects
			(font
				(size 1.27 1.27)
			)
			(justify right bottom)
		)
	)
	(label "VBAT"
		(at 101.6 134.62 0)
		(effects
			(font
				(size 1.27 1.27)
			)
			(justify left bottom)
		)
	)
	(label "USB_UP_N"
		(at 262.89 74.93 0)
		(effects
			(font
				(size 1.27 1.27)
			)
			(justify left bottom)
		)
	)
	(label "VDD33"
		(at 102.87 64.77 0)
		(effects
			(font
				(size 1.27 1.27)
			)
			(justify left bottom)
		)
	)
	(label "USB_DN1_P"
		(at 322.58 82.55 180)
		(effects
			(font
				(size 1.27 1.27)
			)
			(justify right bottom)
		)
	)
	(label "USB_BYP_P"
		(at 284.48 154.94 0)
		(effects
			(font
				(size 1.27 1.27)
			)
			(justify left bottom)
		)
	)
	(label "ULPI.CLK"
		(at 72.39 92.71 0)
		(effects
			(font
				(size 1.27 1.27)
			)
			(justify left bottom)
		)
	)
	(label "USB_N"
		(at 241.3 153.67 0)
		(effects
			(font
				(size 1.27 1.27)
			)
			(justify left bottom)
		)
	)
	(label "REF_CLK"
		(at 215.9 264.16 180)
		(effects
			(font
				(size 1.27 1.27)
			)
			(justify right bottom)
		)
	)
	(label "USB_UP_N"
		(at 285.75 149.86 180)
		(effects
			(font
				(size 1.27 1.27)
			)
			(justify right bottom)
		)
	)
	(label "WL_BT.D_P"
		(at 310.515 68.58 0)
		(effects
			(font
				(size 1.27 1.27)
			)
			(justify left bottom)
		)
	)
	(label "ULPI.STP"
		(at 72.39 95.25 0)
		(effects
			(font
				(size 1.27 1.27)
			)
			(justify left bottom)
		)
	)
	(label "CONN.D_P"
		(at 333.375 151.13 0)
		(effects
			(font
				(size 1.27 1.27)
			)
			(justify left bottom)
		)
	)
	(label "RESETB"
		(at 167.64 186.69 180)
		(effects
			(font
				(size 1.27 1.27)
			)
			(justify right bottom)
		)
	)
	(label "REF_CLK"
		(at 266.7 82.55 0)
		(effects
			(font
				(size 1.27 1.27)
			)
			(justify left bottom)
		)
	)
	(label "REF_CLK"
		(at 142.24 86.36 180)
		(effects
			(font
				(size 1.27 1.27)
			)
			(justify right bottom)
		)
	)
	(label "USB_DN1_N"
		(at 322.58 85.09 180)
		(effects
			(font
				(size 1.27 1.27)
			)
			(justify right bottom)
		)
	)
	(label "ULPI.RESET"
		(at 121.92 195.58 0)
		(effects
			(font
				(size 1.27 1.27)
			)
			(justify left bottom)
		)
	)
	(label "USB_DN1_N"
		(at 290.83 149.86 0)
		(effects
			(font
				(size 1.27 1.27)
			)
			(justify left bottom)
		)
	)
	(label "ULPI.DIR"
		(at 72.39 100.33 0)
		(effects
			(font
				(size 1.27 1.27)
			)
			(justify left bottom)
		)
	)
	(label "ULPI.NXT"
		(at 72.39 97.79 0)
		(effects
			(font
				(size 1.27 1.27)
			)
			(justify left bottom)
		)
	)
	(label "USB_N"
		(at 138.43 73.66 180)
		(effects
			(font
				(size 1.27 1.27)
			)
			(justify right bottom)
		)
	)
	(label "~{HUB_RST}"
		(at 267.97 64.77 0)
		(effects
			(font
				(size 1.27 1.27)
			)
			(justify left bottom)
		)
	)
	(label "VDDIO"
		(at 54.61 133.35 0)
		(effects
			(font
				(size 1.27 1.27)
			)
			(justify left bottom)
		)
	)
	(label "USB_BYP_N"
		(at 284.48 157.48 0)
		(effects
			(font
				(size 1.27 1.27)
			)
			(justify left bottom)
		)
	)
	(label "ULPI.DATA7"
		(at 93.98 88.9 0)
		(effects
			(font
				(size 1.27 1.27)
			)
			(justify left bottom)
		)
	)
	(label "USB_DN1_P"
		(at 290.83 147.32 0)
		(effects
			(font
				(size 1.27 1.27)
			)
			(justify left bottom)
		)
	)
	(label "USB_UP_P"
		(at 285.75 147.32 180)
		(effects
			(font
				(size 1.27 1.27)
			)
			(justify right bottom)
		)
	)
	(label "ULPI.DATA5"
		(at 93.98 83.82 0)
		(effects
			(font
				(size 1.27 1.27)
			)
			(justify left bottom)
		)
	)
	(label "ULPI.DATA2"
		(at 93.98 76.2 0)
		(effects
			(font
				(size 1.27 1.27)
			)
			(justify left bottom)
		)
	)
	(label "USB_UP_P"
		(at 262.89 72.39 0)
		(effects
			(font
				(size 1.27 1.27)
			)
			(justify left bottom)
		)
	)
	(label "VDD18"
		(at 118.11 134.62 0)
		(effects
			(font
				(size 1.27 1.27)
			)
			(justify left bottom)
		)
	)
	(label "VDD18"
		(at 102.87 67.31 0)
		(effects
			(font
				(size 1.27 1.27)
			)
			(justify left bottom)
		)
	)
	(label "VDDIO"
		(at 138.43 67.31 180)
		(effects
			(font
				(size 1.27 1.27)
			)
			(justify right bottom)
		)
	)
	(label "VDDIO"
		(at 77.47 83.82 0)
		(effects
			(font
				(size 1.27 1.27)
			)
			(justify left bottom)
		)
	)
	(label "VBAT"
		(at 138.43 64.77 180)
		(effects
			(font
				(size 1.27 1.27)
			)
			(justify right bottom)
		)
	)
	(label "ULPI.DATA3"
		(at 93.98 78.74 0)
		(effects
			(font
				(size 1.27 1.27)
			)
			(justify left bottom)
		)
	)
	(label "ULPI.DATA1"
		(at 93.98 73.66 0)
		(effects
			(font
				(size 1.27 1.27)
			)
			(justify left bottom)
		)
	)
	(label "ULPI.DATA6"
		(at 93.98 86.36 0)
		(effects
			(font
				(size 1.27 1.27)
			)
			(justify left bottom)
		)
	)
	(label "USB_P"
		(at 138.43 71.12 180)
		(effects
			(font
				(size 1.27 1.27)
			)
			(justify right bottom)
		)
	)
	(label "ULPI.DATA0"
		(at 93.98 71.12 0)
		(effects
			(font
				(size 1.27 1.27)
			)
			(justify left bottom)
		)
	)
	(label "CONN.D_N"
		(at 333.375 153.67 0)
		(effects
			(font
				(size 1.27 1.27)
			)
			(justify left bottom)
		)
	)
	(global_label "VBUS"
		(shape input)
		(at 153.67 49.53 180)
		(fields_autoplaced yes)
		(effects
			(font
				(size 1.27 1.27)
			)
			(justify right)
		)
		(property "Intersheetrefs" "${INTERSHEET_REFS}"
			(at 145.7862 49.53 0)
			(effects
				(font
					(size 1.27 1.27)
				)
				(justify right)
			)
		)
	)
	(global_label "USB_OTG_ID"
		(shape input)
		(at 274.32 68.58 180)
		(fields_autoplaced yes)
		(effects
			(font
				(size 1.27 1.27)
			)
			(justify right)
		)
		(property "Intersheetrefs" "${INTERSHEET_REFS}"
			(at 260.1467 68.58 0)
			(effects
				(font
					(size 1.27 1.27)
				)
				(justify right)
			)
		)
	)
	(global_label "VBUS"
		(shape input)
		(at 143.51 72.39 0)
		(fields_autoplaced yes)
		(effects
			(font
				(size 1.27 1.27)
			)
			(justify left)
		)
		(property "Intersheetrefs" "${INTERSHEET_REFS}"
			(at 151.3938 72.39 0)
			(effects
				(font
					(size 1.27 1.27)
				)
				(justify left)
			)
		)
	)
	(global_label "USB_OTG_ID"
		(shape input)
		(at 252.73 160.02 180)
		(fields_autoplaced yes)
		(effects
			(font
				(size 1.27 1.27)
			)
			(justify right)
		)
		(property "Intersheetrefs" "${INTERSHEET_REFS}"
			(at 238.5567 160.02 0)
			(effects
				(font
					(size 1.27 1.27)
				)
				(justify right)
			)
		)
	)
	(global_label "USB_OTG_ID"
		(shape input)
		(at 143.51 78.74 0)
		(fields_autoplaced yes)
		(effects
			(font
				(size 1.27 1.27)
			)
			(justify left)
		)
		(property "Intersheetrefs" "${INTERSHEET_REFS}"
			(at 157.6833 78.74 0)
			(effects
				(font
					(size 1.27 1.27)
				)
				(justify left)
			)
		)
	)
	(global_label "USB_OTG_ID"
		(shape input)
		(at 72.39 187.96 180)
		(fields_autoplaced yes)
		(effects
			(font
				(size 1.27 1.27)
			)
			(justify right)
		)
		(property "Intersheetrefs" "${INTERSHEET_REFS}"
			(at 58.2167 187.96 0)
			(effects
				(font
					(size 1.27 1.27)
				)
				(justify right)
			)
		)
	)
	(global_label "USB_OTG_ID"
		(shape input)
		(at 323.85 160.02 0)
		(fields_autoplaced yes)
		(effects
			(font
				(size 1.27 1.27)
			)
			(justify left)
		)
		(property "Intersheetrefs" "${INTERSHEET_REFS}"
			(at 338.0233 160.02 0)
			(effects
				(font
					(size 1.27 1.27)
				)
				(justify left)
			)
		)
	)
	(hierarchical_label "ULPI{ULPI}"
		(shape input)
		(at 116.84 190.5 180)
		(effects
			(font
				(size 1.27 1.27)
			)
			(justify right)
		)
	)
	(hierarchical_label "ULPI{ULPI}"
		(shape input)
		(at 88.9 66.04 180)
		(effects
			(font
				(size 1.27 1.27)
			)
			(justify right)
		)
	)
	(hierarchical_label "ULPI{ULPI}"
		(shape input)
		(at 67.31 87.63 180)
		(effects
			(font
				(size 1.27 1.27)
			)
			(justify right)
		)
	)
	(hierarchical_label "WL_BT{USB}"
		(shape input)
		(at 327.66 62.23 0)
		(effects
			(font
				(size 1.27 1.27)
			)
			(justify left)
		)
	)
	(hierarchical_label "CONN{USB}"
		(shape input)
		(at 360.68 146.05 0)
		(effects
			(font
				(size 1.27 1.27)
			)
			(justify left)
		)
	)
	(symbol
		(lib_id "antmicropower:+3V3")
		(at 271.78 50.8 0)
		(mirror y)
		(unit 1)
		(exclude_from_sim no)
		(in_bom yes)
		(on_board yes)
		(dnp no)
		(property "Reference" "#PWR0283"
			(at 271.78 54.61 0)
			(effects
				(font
					(size 1.27 1.27)
				)
				(hide yes)
			)
		)
		(property "Value" "+3V3"
			(at 271.78 46.99 0)
			(effects
				(font
					(size 1.27 1.27)
				)
			)
		)
		(property "Footprint" ""
			(at 271.78 50.8 0)
			(effects
				(font
					(size 1.27 1.27)
				)
				(hide yes)
			)
		)
		(property "Datasheet" ""
			(at 271.78 50.8 0)
			(effects
				(font
					(size 1.27 1.27)
				)
				(hide yes)
			)
		)
		(property "Description" ""
			(at 271.78 50.8 0)
			(effects
				(font
					(size 1.27 1.27)
				)
				(hide yes)
			)
		)
		(property "Author" "Antmicro"
			(at 256.54 53.34 0)
			(effects
				(font
					(size 1.27 1.27)
					(thickness 0.15)
				)
				(justify left bottom)
				(hide yes)
			)
		)
		(property "License" "Apache-2.0"
			(at 256.54 55.88 0)
			(effects
				(font
					(size 1.27 1.27)
					(thickness 0.15)
				)
				(justify left bottom)
				(hide yes)
			)
		)
		(pin "1"
		)
		(instances
			(project "polarfire-som"
				(path ""
					(reference "#PWR0283")
					(unit 1)
				)
			)
		)
	)
	(symbol
		(lib_id "antmicroInterfaceAnalogSwitchesSpecialPurpose:PI3USB102GZLEX")
		(at 322.58 146.05 0)
		(mirror y)
		(unit 1)
		(exclude_from_sim no)
		(in_bom yes)
		(on_board yes)
		(dnp no)
		(property "Reference" "U22"
			(at 304.8 140.97 0)
			(effects
				(font
					(size 1.27 1.27)
				)
				(justify right)
			)
		)
		(property "Value" "PI3USB102GZLEX"
			(at 304.8 143.5069 0)
			(effects
				(font
					(size 1.27 1.27)
				)
				(justify right)
			)
		)
		(property "Footprint" "antmicro-footprints:UQFN-10_1.4x1.8x0.5mm_P0.4mm"
			(at 322.58 166.37 0)
			(effects
				(font
					(size 1.27 1.27)
				)
				(hide yes)
			)
		)
		(property "Datasheet" "https://www.diodes.com/assets/Datasheets/PI3USB102G.pdf"
			(at 320.04 172.72 0)
			(effects
				(font
					(size 1.27 1.27)
				)
				(hide yes)
			)
		)
		(property "Description" "USB Switch IC 1 Channel 10-TQFN (1.3x1.6)"
			(at 322.58 146.05 0)
			(effects
				(font
					(size 1.27 1.27)
				)
				(hide yes)
			)
		)
		(property "MPN" "PI3USB102GZLEX"
			(at 287.02 161.29 0)
			(effects
				(font
					(size 1.27 1.27)
					(thickness 0.15)
				)
				(justify left bottom)
				(hide yes)
			)
		)
		(property "Manufacturer" "Diodes Incorporated"
			(at 287.02 163.83 0)
			(effects
				(font
					(size 1.27 1.27)
					(thickness 0.15)
				)
				(justify left bottom)
				(hide yes)
			)
		)
		(property "Author" "Antmicro"
			(at 287.02 166.37 0)
			(effects
				(font
					(size 1.27 1.27)
					(thickness 0.15)
				)
				(justify left bottom)
				(hide yes)
			)
		)
		(property "License" "Apache-2.0"
			(at 287.02 168.91 0)
			(effects
				(font
					(size 1.27 1.27)
					(thickness 0.15)
				)
				(justify left bottom)
				(hide yes)
			)
		)
		(pin "1"
		)
		(pin "10"
		)
		(pin "2"
		)
		(pin "3"
		)
		(pin "4"
		)
		(pin "5"
		)
		(pin "6"
		)
		(pin "7"
		)
		(pin "8"
		)
		(pin "9"
		)
		(instances
			(project "polarfire-som"
				(path ""
					(reference "U22")
					(unit 1)
				)
			)
		)
	)
	(symbol
		(lib_id "antmicropower:GND")
		(at 322.58 106.68 0)
		(unit 1)
		(exclude_from_sim no)
		(in_bom yes)
		(on_board yes)
		(dnp no)
		(fields_autoplaced yes)
		(property "Reference" "#PWR0161"
			(at 331.47 109.22 0)
			(effects
				(font
					(size 1.27 1.27)
					(thickness 0.15)
				)
				(justify left bottom)
				(hide yes)
			)
		)
		(property "Value" "GND"
			(at 322.58 111.76 0)
			(effects
				(font
					(size 1.27 1.27)
					(thickness 0.15)
				)
			)
		)
		(property "Footprint" ""
			(at 331.47 114.3 0)
			(effects
				(font
					(size 1.27 1.27)
					(thickness 0.15)
				)
				(justify left bottom)
				(hide yes)
			)
		)
		(property "Datasheet" ""
			(at 331.47 119.38 0)
			(effects
				(font
					(size 1.27 1.27)
					(thickness 0.15)
				)
				(justify left bottom)
				(hide yes)
			)
		)
		(property "Description" ""
			(at 322.58 106.68 0)
			(effects
				(font
					(size 1.27 1.27)
				)
				(hide yes)
			)
		)
		(property "Author" "Antmicro"
			(at 331.47 114.3 0)
			(effects
				(font
					(size 1.27 1.27)
					(thickness 0.15)
				)
				(justify left bottom)
				(hide yes)
			)
		)
		(property "License" "Apache-2.0"
			(at 331.47 116.84 0)
			(effects
				(font
					(size 1.27 1.27)
					(thickness 0.15)
				)
				(justify left bottom)
				(hide yes)
			)
		)
		(pin "1"
		)
		(instances
			(project "polarfire-som"
				(path ""
					(reference "#PWR0161")
					(unit 1)
				)
			)
		)
	)
	(symbol
		(lib_id "antmicroResistors0402:R_8k06_0402")
		(at 137.16 95.25 0)
		(unit 1)
		(exclude_from_sim no)
		(in_bom yes)
		(on_board yes)
		(dnp no)
		(property "Reference" "R18"
			(at 144.78 93.98 0)
			(effects
				(font
					(size 1.27 1.27)
					(thickness 0.15)
				)
			)
		)
		(property "Value" "R_8k06_0402"
			(at 157.48 107.95 0)
			(effects
				(font
					(size 1.27 1.27)
					(thickness 0.15)
				)
				(justify left bottom)
				(hide yes)
			)
		)
		(property "Footprint" "antmicro-footprints:R_0402_1005Metric"
			(at 157.48 110.49 0)
			(effects
				(font
					(size 1.27 1.27)
					(thickness 0.15)
				)
				(justify left bottom)
				(hide yes)
			)
		)
		(property "Datasheet" "https://www.bourns.com/docs/product-datasheets/cr.pdf"
			(at 157.48 113.03 0)
			(effects
				(font
					(size 1.27 1.27)
					(thickness 0.15)
				)
				(justify left bottom)
				(hide yes)
			)
		)
		(property "Description" "SMD Chip Resistor, 8.06 kohm, ± 1%, 63 mW, 0402 [1005 Metric], Thick Film, General Purpose"
			(at 137.16 95.25 0)
			(effects
				(font
					(size 1.27 1.27)
				)
				(hide yes)
			)
		)
		(property "MPN" "CR0402-FX-8061GLF"
			(at 157.48 115.57 0)
			(effects
				(font
					(size 1.27 1.27)
					(thickness 0.15)
				)
				(justify left bottom)
				(hide yes)
			)
		)
		(property "Manufacturer" "Bourns"
			(at 157.48 118.11 0)
			(effects
				(font
					(size 1.27 1.27)
					(thickness 0.15)
				)
				(justify left bottom)
				(hide yes)
			)
		)
		(property "License" "Apache-2.0"
			(at 157.48 120.65 0)
			(effects
				(font
					(size 1.27 1.27)
					(thickness 0.15)
				)
				(justify left bottom)
				(hide yes)
			)
		)
		(property "Author" "Antmicro"
			(at 157.48 123.19 0)
			(effects
				(font
					(size 1.27 1.27)
					(thickness 0.15)
				)
				(justify left bottom)
				(hide yes)
			)
		)
		(property "Val" "8k06"
			(at 134.62 93.98 0)
			(effects
				(font
					(size 1.27 1.27)
					(thickness 0.15)
				)
			)
		)
		(property "Tolerance" "1%"
			(at 157.48 105.41 0)
			(effects
				(font
					(size 1.27 1.27)
				)
				(justify left bottom)
				(hide yes)
			)
		)
		(property "Public" ""
			(at 157.48 125.73 0)
			(effects
				(font
					(size 1.27 1.27)
				)
				(justify left bottom)
				(hide yes)
			)
		)
		(pin "1"
		)
		(pin "2"
		)
		(instances
			(project "polarfire-som"
				(path ""
					(reference "R18")
					(unit 1)
				)
			)
		)
	)
	(symbol
		(lib_id "antmicroInterfaceControllers:USB3315-CP-TR")
		(at 130.81 64.77 0)
		(mirror y)
		(unit 1)
		(exclude_from_sim no)
		(in_bom yes)
		(on_board yes)
		(dnp no)
		(property "Reference" "U13"
			(at 120.65 57.15 0)
			(effects
				(font
					(size 1.27 1.27)
					(thickness 0.15)
				)
			)
		)
		(property "Value" "USB3315-CP-TR"
			(at 120.65 59.69 0)
			(effects
				(font
					(size 1.27 1.27)
					(thickness 0.15)
				)
			)
		)
		(property "Footprint" "antmicro-footprints:QFN-24-1EP_4x4mm_P0.5_EP2.5x2.5mm"
			(at 85.09 72.39 0)
			(effects
				(font
					(size 1.27 1.27)
					(thickness 0.15)
				)
				(justify left bottom)
				(hide yes)
			)
		)
		(property "Datasheet" "https://ww1.microchip.com/downloads/aemDocuments/documents/OTH/ProductDocuments/DataSheets/00002364A.pdf"
			(at 85.09 74.93 0)
			(effects
				(font
					(size 1.27 1.27)
					(thickness 0.15)
				)
				(justify left bottom)
				(hide yes)
			)
		)
		(property "Description" "USB Interface, USB PHY Transceiver, USB 2.0, 3 V, 5.5 V, QFN, 24 Pins"
			(at 130.81 64.77 0)
			(effects
				(font
					(size 1.27 1.27)
				)
				(hide yes)
			)
		)
		(property "MPN" "USB3315-CP-TR"
			(at 85.09 77.47 0)
			(effects
				(font
					(size 1.27 1.27)
					(thickness 0.15)
				)
				(justify left bottom)
				(hide yes)
			)
		)
		(property "Manufacturer" "Microchip Technology"
			(at 85.09 80.01 0)
			(effects
				(font
					(size 1.27 1.27)
					(thickness 0.15)
				)
				(justify left bottom)
				(hide yes)
			)
		)
		(property "Author" "Antmicro"
			(at 85.09 82.55 0)
			(effects
				(font
					(size 1.27 1.27)
					(thickness 0.15)
				)
				(justify left bottom)
				(hide yes)
			)
		)
		(property "License" "Apache-2.0"
			(at 85.09 85.09 0)
			(effects
				(font
					(size 1.27 1.27)
					(thickness 0.15)
				)
				(justify left bottom)
				(hide yes)
			)
		)
		(pin "16"
		)
		(pin "7"
		)
		(pin "18"
		)
		(pin "24"
		)
		(pin "22"
		)
		(pin "3"
		)
		(pin "9"
		)
		(pin "23"
		)
		(pin "11"
		)
		(pin "12"
		)
		(pin "19"
		)
		(pin "13"
		)
		(pin "21"
		)
		(pin "15"
		)
		(pin "4"
		)
		(pin "20"
		)
		(pin "5"
		)
		(pin "8"
		)
		(pin "17"
		)
		(pin "25"
		)
		(pin "2"
		)
		(pin "6"
		)
		(pin "14"
		)
		(pin "1"
		)
		(pin "10"
		)
		(instances
			(project "polarfire-som"
				(path ""
					(reference "U13")
					(unit 1)
				)
			)
		)
	)
	(symbol
		(lib_id "antmicroResistors0402:R_100k_0402")
		(at 265.43 62.23 270)
		(mirror x)
		(unit 1)
		(exclude_from_sim no)
		(in_bom yes)
		(on_board yes)
		(dnp no)
		(property "Reference" "R164"
			(at 264.16 58.42 90)
			(effects
				(font
					(size 1.27 1.27)
					(thickness 0.15)
				)
				(justify right)
			)
		)
		(property "Value" "R_100k_0402"
			(at 252.73 41.91 0)
			(effects
				(font
					(size 1.27 1.27)
					(thickness 0.15)
				)
				(justify left bottom)
				(hide yes)
			)
		)
		(property "Footprint" "antmicro-footprints:R_0402_1005Metric"
			(at 250.19 41.91 0)
			(effects
				(font
					(size 1.27 1.27)
					(thickness 0.15)
				)
				(justify left bottom)
				(hide yes)
			)
		)
		(property "Datasheet" "https://www.bourns.com/docs/product-datasheets/cr.pdf"
			(at 247.65 41.91 0)
			(effects
				(font
					(size 1.27 1.27)
					(thickness 0.15)
				)
				(justify left bottom)
				(hide yes)
			)
		)
		(property "Description" "SMD Chip Resistor, 100 kohm, ± 1%, 62.5 mW, 0402 [1005 Metric], Thick Film, General Purpose"
			(at 265.43 62.23 0)
			(effects
				(font
					(size 1.27 1.27)
				)
				(hide yes)
			)
		)
		(property "MPN" "CR0402-FX-1003GLF"
			(at 245.11 41.91 0)
			(effects
				(font
					(size 1.27 1.27)
					(thickness 0.15)
				)
				(justify left bottom)
				(hide yes)
			)
		)
		(property "Manufacturer" "Bourns"
			(at 242.57 41.91 0)
			(effects
				(font
					(size 1.27 1.27)
					(thickness 0.15)
				)
				(justify left bottom)
				(hide yes)
			)
		)
		(property "License" "Apache-2.0"
			(at 240.03 41.91 0)
			(effects
				(font
					(size 1.27 1.27)
					(thickness 0.15)
				)
				(justify left bottom)
				(hide yes)
			)
		)
		(property "Author" "Antmicro"
			(at 237.49 41.91 0)
			(effects
				(font
					(size 1.27 1.27)
					(thickness 0.15)
				)
				(justify left bottom)
				(hide yes)
			)
		)
		(property "Val" "100k"
			(at 264.16 60.96 90)
			(effects
				(font
					(size 1.27 1.27)
					(thickness 0.15)
				)
				(justify right)
			)
		)
		(property "Tolerance" "1%"
			(at 255.27 41.91 0)
			(effects
				(font
					(size 1.27 1.27)
				)
				(justify left bottom)
				(hide yes)
			)
		)
		(property "Public" ""
			(at 234.95 41.91 0)
			(effects
				(font
					(size 1.27 1.27)
				)
				(justify left bottom)
				(hide yes)
			)
		)
		(pin "1"
		)
		(pin "2"
		)
		(instances
			(project "polarfire-som"
				(path ""
					(reference "R164")
					(unit 1)
				)
			)
		)
	)
	(symbol
		(lib_id "antmicropower:GND")
		(at 299.72 163.83 0)
		(unit 1)
		(exclude_from_sim no)
		(in_bom yes)
		(on_board yes)
		(dnp no)
		(fields_autoplaced yes)
		(property "Reference" "#PWR0124"
			(at 308.61 166.37 0)
			(effects
				(font
					(size 1.27 1.27)
					(thickness 0.15)
				)
				(justify left bottom)
				(hide yes)
			)
		)
		(property "Value" "GND"
			(at 299.72 168.91 0)
			(effects
				(font
					(size 1.27 1.27)
					(thickness 0.15)
				)
			)
		)
		(property "Footprint" ""
			(at 308.61 171.45 0)
			(effects
				(font
					(size 1.27 1.27)
					(thickness 0.15)
				)
				(justify left bottom)
				(hide yes)
			)
		)
		(property "Datasheet" ""
			(at 308.61 176.53 0)
			(effects
				(font
					(size 1.27 1.27)
					(thickness 0.15)
				)
				(justify left bottom)
				(hide yes)
			)
		)
		(property "Description" ""
			(at 299.72 163.83 0)
			(effects
				(font
					(size 1.27 1.27)
				)
				(hide yes)
			)
		)
		(property "Author" "Antmicro"
			(at 308.61 171.45 0)
			(effects
				(font
					(size 1.27 1.27)
					(thickness 0.15)
				)
				(justify left bottom)
				(hide yes)
			)
		)
		(property "License" "Apache-2.0"
			(at 308.61 173.99 0)
			(effects
				(font
					(size 1.27 1.27)
					(thickness 0.15)
				)
				(justify left bottom)
				(hide yes)
			)
		)
		(pin "1"
		)
		(instances
			(project "polarfire-som"
				(path ""
					(reference "#PWR0124")
					(unit 1)
				)
			)
		)
	)
	(symbol
		(lib_id "antmicropower:PWR_FLAG")
		(at 139.7 67.31 270)
		(mirror x)
		(unit 1)
		(exclude_from_sim no)
		(in_bom yes)
		(on_board yes)
		(dnp no)
		(property "Reference" "#FLG07"
			(at 141.605 67.31 0)
			(effects
				(font
					(size 1.27 1.27)
				)
				(hide yes)
			)
		)
		(property "Value" "PWR_FLAG"
			(at 147.32 67.31 90)
			(effects
				(font
					(size 1.27 1.27)
				)
			)
		)
		(property "Footprint" ""
			(at 139.7 67.31 0)
			(effects
				(font
					(size 1.27 1.27)
				)
				(hide yes)
			)
		)
		(property "Datasheet" ""
			(at 139.7 67.31 0)
			(effects
				(font
					(size 1.27 1.27)
				)
				(hide yes)
			)
		)
		(property "Description" ""
			(at 139.7 67.31 0)
			(effects
				(font
					(size 1.27 1.27)
				)
				(hide yes)
			)
		)
		(pin "1"
		)
		(instances
			(project "polarfire-som"
				(path ""
					(reference "#FLG07")
					(unit 1)
				)
			)
		)
	)
	(symbol
		(lib_id "antmicropower:GND")
		(at 151.13 204.47 0)
		(unit 1)
		(exclude_from_sim no)
		(in_bom yes)
		(on_board yes)
		(dnp no)
		(fields_autoplaced yes)
		(property "Reference" "#PWR0208"
			(at 160.02 207.01 0)
			(effects
				(font
					(size 1.27 1.27)
					(thickness 0.15)
				)
				(justify left bottom)
				(hide yes)
			)
		)
		(property "Value" "GND"
			(at 151.13 209.55 0)
			(effects
				(font
					(size 1.27 1.27)
					(thickness 0.15)
				)
			)
		)
		(property "Footprint" ""
			(at 160.02 212.09 0)
			(effects
				(font
					(size 1.27 1.27)
					(thickness 0.15)
				)
				(justify left bottom)
				(hide yes)
			)
		)
		(property "Datasheet" ""
			(at 160.02 217.17 0)
			(effects
				(font
					(size 1.27 1.27)
					(thickness 0.15)
				)
				(justify left bottom)
				(hide yes)
			)
		)
		(property "Description" ""
			(at 151.13 204.47 0)
			(effects
				(font
					(size 1.27 1.27)
				)
				(hide yes)
			)
		)
		(property "Author" "Antmicro"
			(at 160.02 212.09 0)
			(effects
				(font
					(size 1.27 1.27)
					(thickness 0.15)
				)
				(justify left bottom)
				(hide yes)
			)
		)
		(property "License" "Apache-2.0"
			(at 160.02 214.63 0)
			(effects
				(font
					(size 1.27 1.27)
					(thickness 0.15)
				)
				(justify left bottom)
				(hide yes)
			)
		)
		(pin "1"
		)
		(instances
			(project "polarfire-som"
				(path ""
					(reference "#PWR0208")
					(unit 1)
				)
			)
		)
	)
	(symbol
		(lib_id "antmicroCapacitors0402:C_100n_0402")
		(at 60.96 140.97 90)
		(unit 1)
		(exclude_from_sim no)
		(in_bom yes)
		(on_board yes)
		(dnp no)
		(property "Reference" "C184"
			(at 60.96 135.89 90)
			(effects
				(font
					(size 1.27 1.27)
					(thickness 0.15)
				)
				(justify right)
			)
		)
		(property "Value" "C_100n_0402"
			(at 71.12 120.65 0)
			(effects
				(font
					(size 1.27 1.27)
					(thickness 0.15)
				)
				(justify left bottom)
				(hide yes)
			)
		)
		(property "Footprint" "antmicro-footprints:C_0402_1005Metric"
			(at 73.66 120.65 0)
			(effects
				(font
					(size 1.27 1.27)
					(thickness 0.15)
				)
				(justify left bottom)
				(hide yes)
			)
		)
		(property "Datasheet" "https://www.murata.com/products/productdetail?partno=GRM155R61H104KE14%23"
			(at 76.2 120.65 0)
			(effects
				(font
					(size 1.27 1.27)
					(thickness 0.15)
				)
				(justify left bottom)
				(hide yes)
			)
		)
		(property "Description" "SMD Multilayer Ceramic Capacitor, 0.1 µF, 50 V, 0402 [1005 Metric], ± 10%, X5R, GRM Series"
			(at 60.96 140.97 0)
			(effects
				(font
					(size 1.27 1.27)
				)
				(hide yes)
			)
		)
		(property "MPN" "GRM155R61H104KE14D"
			(at 78.74 120.65 0)
			(effects
				(font
					(size 1.27 1.27)
					(thickness 0.15)
				)
				(justify left bottom)
				(hide yes)
			)
		)
		(property "Manufacturer" "Murata"
			(at 81.28 120.65 0)
			(effects
				(font
					(size 1.27 1.27)
					(thickness 0.15)
				)
				(justify left bottom)
				(hide yes)
			)
		)
		(property "License" "Apache-2.0"
			(at 83.82 120.65 0)
			(effects
				(font
					(size 1.27 1.27)
					(thickness 0.15)
				)
				(justify left bottom)
				(hide yes)
			)
		)
		(property "Author" "Antmicro"
			(at 86.36 120.65 0)
			(effects
				(font
					(size 1.27 1.27)
					(thickness 0.15)
				)
				(justify left bottom)
				(hide yes)
			)
		)
		(property "Val" "100n"
			(at 66.04 139.7 90)
			(effects
				(font
					(size 1.27 1.27)
					(thickness 0.15)
				)
				(justify left bottom)
			)
		)
		(property "Voltage" "50V"
			(at 88.9 120.65 0)
			(effects
				(font
					(size 1.27 1.27)
				)
				(justify left bottom)
				(hide yes)
			)
		)
		(property "Dielectric" "X5R"
			(at 91.44 120.65 0)
			(effects
				(font
					(size 1.27 1.27)
				)
				(justify left bottom)
				(hide yes)
			)
		)
		(property "Public" ""
			(at 93.98 120.65 0)
			(effects
				(font
					(size 1.27 1.27)
				)
				(justify left bottom)
				(hide yes)
			)
		)
		(pin "1"
		)
		(pin "2"
		)
		(instances
			(project "polarfire-som"
				(path ""
					(reference "C184")
					(unit 1)
				)
			)
		)
	)
	(symbol
		(lib_id "antmicroCapacitors0402:C_100n_0402")
		(at 322.58 102.87 90)
		(unit 1)
		(exclude_from_sim no)
		(in_bom yes)
		(on_board yes)
		(dnp no)
		(property "Reference" "C217"
			(at 325.12 99.0535 90)
			(effects
				(font
					(size 1.27 1.27)
					(thickness 0.15)
				)
				(justify right)
			)
		)
		(property "Value" "C_100n_0402"
			(at 332.74 82.55 0)
			(effects
				(font
					(size 1.27 1.27)
					(thickness 0.15)
				)
				(justify left bottom)
				(hide yes)
			)
		)
		(property "Footprint" "antmicro-footprints:C_0402_1005Metric"
			(at 335.28 82.55 0)
			(effects
				(font
					(size 1.27 1.27)
					(thickness 0.15)
				)
				(justify left bottom)
				(hide yes)
			)
		)
		(property "Datasheet" "https://www.murata.com/products/productdetail?partno=GRM155R61H104KE14%23"
			(at 337.82 82.55 0)
			(effects
				(font
					(size 1.27 1.27)
					(thickness 0.15)
				)
				(justify left bottom)
				(hide yes)
			)
		)
		(property "Description" "SMD Multilayer Ceramic Capacitor, 0.1 µF, 50 V, 0402 [1005 Metric], ± 10%, X5R, GRM Series"
			(at 322.58 102.87 0)
			(effects
				(font
					(size 1.27 1.27)
				)
				(hide yes)
			)
		)
		(property "MPN" "GRM155R61H104KE14D"
			(at 340.36 82.55 0)
			(effects
				(font
					(size 1.27 1.27)
					(thickness 0.15)
				)
				(justify left bottom)
				(hide yes)
			)
		)
		(property "Manufacturer" "Murata"
			(at 342.9 82.55 0)
			(effects
				(font
					(size 1.27 1.27)
					(thickness 0.15)
				)
				(justify left bottom)
				(hide yes)
			)
		)
		(property "License" "Apache-2.0"
			(at 345.44 82.55 0)
			(effects
				(font
					(size 1.27 1.27)
					(thickness 0.15)
				)
				(justify left bottom)
				(hide yes)
			)
		)
		(property "Author" "Antmicro"
			(at 347.98 82.55 0)
			(effects
				(font
					(size 1.27 1.27)
					(thickness 0.15)
				)
				(justify left bottom)
				(hide yes)
			)
		)
		(property "Val" "100n"
			(at 330.2 100.965 90)
			(effects
				(font
					(size 1.27 1.27)
					(thickness 0.15)
				)
				(justify left bottom)
			)
		)
		(property "Voltage" "50V"
			(at 350.52 82.55 0)
			(effects
				(font
					(size 1.27 1.27)
				)
				(justify left bottom)
				(hide yes)
			)
		)
		(property "Dielectric" "X5R"
			(at 353.06 82.55 0)
			(effects
				(font
					(size 1.27 1.27)
				)
				(justify left bottom)
				(hide yes)
			)
		)
		(property "Public" ""
			(at 355.6 82.55 0)
			(effects
				(font
					(size 1.27 1.27)
				)
				(justify left bottom)
				(hide yes)
			)
		)
		(pin "1"
		)
		(pin "2"
		)
		(instances
			(project "polarfire-som"
				(path ""
					(reference "C217")
					(unit 1)
				)
			)
		)
	)
	(symbol
		(lib_id "antmicroTVSDiodes:AXGD10402KR")
		(at 74.93 195.58 90)
		(unit 1)
		(exclude_from_sim no)
		(in_bom yes)
		(on_board yes)
		(dnp no)
		(property "Reference" "D4"
			(at 77.47 191.77 90)
			(effects
				(font
					(size 1.27 1.27)
					(thickness 0.15)
				)
				(justify right)
			)
		)
		(property "Value" "AXGD10402KR"
			(at 85.09 170.18 0)
			(effects
				(font
					(size 1.27 1.27)
					(thickness 0.15)
				)
				(justify left bottom)
				(hide yes)
			)
		)
		(property "Footprint" "antmicro-footprints:D_0402_1005Metric"
			(at 87.63 170.18 0)
			(effects
				(font
					(size 1.27 1.27)
					(thickness 0.15)
				)
				(justify left bottom)
				(hide yes)
			)
		)
		(property "Datasheet" "https://www.littelfuse.com/media?resourcetype=datasheets&itemid=020b2bf2-064c-4ff1-a898-b4ec805b2fea&filename=littelfuse-xtremeguard-axgd-datasheet"
			(at 90.17 170.18 0)
			(effects
				(font
					(size 1.27 1.27)
					(thickness 0.15)
				)
				(justify left bottom)
				(hide yes)
			)
		)
		(property "Description" "Bidirectional TVS, 30 kV,  0402, 24 V, 0.04 pF"
			(at 74.93 195.58 0)
			(effects
				(font
					(size 1.27 1.27)
				)
				(hide yes)
			)
		)
		(property "Manufacturer" "Littelfuse"
			(at 92.71 170.18 0)
			(effects
				(font
					(size 1.27 1.27)
					(thickness 0.15)
				)
				(justify left bottom)
				(hide yes)
			)
		)
		(property "MPN" "AXGD10402KR"
			(at 77.47 194.31 90)
			(effects
				(font
					(size 1.27 1.27)
					(thickness 0.15)
				)
				(justify right)
			)
		)
		(property "Author" "Antmicro"
			(at 95.25 170.18 0)
			(effects
				(font
					(size 1.27 1.27)
					(thickness 0.15)
				)
				(justify left bottom)
				(hide yes)
			)
		)
		(property "License" "Apache-2.0"
			(at 97.79 170.18 0)
			(effects
				(font
					(size 1.27 1.27)
					(thickness 0.15)
				)
				(justify left bottom)
				(hide yes)
			)
		)
		(property "Public" ""
			(at 92.71 175.26 0)
			(effects
				(font
					(size 1.27 1.27)
				)
				(justify left bottom)
				(hide yes)
			)
		)
		(pin "1"
		)
		(pin "2"
		)
		(instances
			(project "polarfire-som"
				(path ""
					(reference "D4")
					(unit 1)
				)
			)
		)
	)
	(symbol
		(lib_id "antmicroCapacitors0402:C_1u_0402")
		(at 161.29 140.97 90)
		(unit 1)
		(exclude_from_sim no)
		(in_bom yes)
		(on_board yes)
		(dnp no)
		(fields_autoplaced yes)
		(property "Reference" "C179"
			(at 163.83 137.1535 90)
			(effects
				(font
					(size 1.27 1.27)
					(thickness 0.15)
				)
				(justify right)
			)
		)
		(property "Value" "C_1u_0402"
			(at 171.45 120.65 0)
			(effects
				(font
					(size 1.27 1.27)
					(thickness 0.15)
				)
				(justify left bottom)
				(hide yes)
			)
		)
		(property "Footprint" "antmicro-footprints:C_0402_1005Metric"
			(at 173.99 120.65 0)
			(effects
				(font
					(size 1.27 1.27)
					(thickness 0.15)
				)
				(justify left bottom)
				(hide yes)
			)
		)
		(property "Datasheet" "https://product.tdk.com/en/search/capacitor/ceramic/mlcc/info?part_no=C1005X6S1A105K050BC"
			(at 176.53 120.65 0)
			(effects
				(font
					(size 1.27 1.27)
					(thickness 0.15)
				)
				(justify left bottom)
				(hide yes)
			)
		)
		(property "Description" "SMD Multilayer Ceramic Capacitor, 1 µF, 10 V, 0402 [1005 Metric], ± 10%, X6S, C"
			(at 161.29 140.97 0)
			(effects
				(font
					(size 1.27 1.27)
				)
				(hide yes)
			)
		)
		(property "MPN" "C1005X6S1A105K050BC"
			(at 179.07 120.65 0)
			(effects
				(font
					(size 1.27 1.27)
					(thickness 0.15)
				)
				(justify left bottom)
				(hide yes)
			)
		)
		(property "Manufacturer" "TDK"
			(at 181.61 120.65 0)
			(effects
				(font
					(size 1.27 1.27)
					(thickness 0.15)
				)
				(justify left bottom)
				(hide yes)
			)
		)
		(property "License" "Apache-2.0"
			(at 184.15 120.65 0)
			(effects
				(font
					(size 1.27 1.27)
					(thickness 0.15)
				)
				(justify left bottom)
				(hide yes)
			)
		)
		(property "Author" "Antmicro"
			(at 186.69 120.65 0)
			(effects
				(font
					(size 1.27 1.27)
					(thickness 0.15)
				)
				(justify left bottom)
				(hide yes)
			)
		)
		(property "Val" "1u"
			(at 163.83 139.6935 90)
			(effects
				(font
					(size 1.27 1.27)
					(thickness 0.15)
				)
				(justify right)
			)
		)
		(property "Voltage" ""
			(at 189.23 120.65 0)
			(effects
				(font
					(size 1.27 1.27)
				)
				(justify left bottom)
				(hide yes)
			)
		)
		(property "Dielectric" ""
			(at 191.77 120.65 0)
			(effects
				(font
					(size 1.27 1.27)
				)
				(justify left bottom)
				(hide yes)
			)
		)
		(property "Public" ""
			(at 194.31 120.65 0)
			(effects
				(font
					(size 1.27 1.27)
				)
				(justify left bottom)
				(hide yes)
			)
		)
		(pin "1"
		)
		(pin "2"
		)
		(instances
			(project "polarfire-som"
				(path ""
					(reference "C179")
					(unit 1)
				)
			)
		)
	)
	(symbol
		(lib_id "antmicropower:VDDI")
		(at 151.13 175.26 0)
		(unit 1)
		(exclude_from_sim no)
		(in_bom yes)
		(on_board yes)
		(dnp no)
		(fields_autoplaced yes)
		(property "Reference" "#PWR0339"
			(at 151.13 179.07 0)
			(effects
				(font
					(size 1.27 1.27)
				)
				(hide yes)
			)
		)
		(property "Value" "VDD"
			(at 151.13 170.815 0)
			(effects
				(font
					(size 1.27 1.27)
				)
			)
		)
		(property "Footprint" ""
			(at 151.13 175.26 0)
			(effects
				(font
					(size 1.27 1.27)
				)
				(hide yes)
			)
		)
		(property "Datasheet" ""
			(at 151.13 175.26 0)
			(effects
				(font
					(size 1.27 1.27)
				)
				(hide yes)
			)
		)
		(property "Description" ""
			(at 151.13 175.26 0)
			(effects
				(font
					(size 1.27 1.27)
				)
				(hide yes)
			)
		)
		(pin "1"
		)
		(instances
			(project "polarfire-som"
				(path ""
					(reference "#PWR0339")
					(unit 1)
				)
			)
		)
	)
	(symbol
		(lib_id "antmicroResistors0402:R_270k_0402")
		(at 82.55 90.17 270)
		(mirror x)
		(unit 1)
		(exclude_from_sim no)
		(in_bom yes)
		(on_board yes)
		(dnp no)
		(fields_autoplaced yes)
		(property "Reference" "R66"
			(at 80.01 86.3599 90)
			(effects
				(font
					(size 1.27 1.27)
					(thickness 0.15)
				)
				(justify right)
			)
		)
		(property "Value" "R_270k_0402"
			(at 69.85 69.85 0)
			(effects
				(font
					(size 1.27 1.27)
					(thickness 0.15)
				)
				(justify left bottom)
				(hide yes)
			)
		)
		(property "Footprint" "antmicro-footprints:R_0402_1005Metric"
			(at 67.31 69.85 0)
			(effects
				(font
					(size 1.27 1.27)
					(thickness 0.15)
				)
				(justify left bottom)
				(hide yes)
			)
		)
		(property "Datasheet" "https://www.bourns.com/docs/product-datasheets/cr.pdf"
			(at 64.77 69.85 0)
			(effects
				(font
					(size 1.27 1.27)
					(thickness 0.15)
				)
				(justify left bottom)
				(hide yes)
			)
		)
		(property "Description" "SMD Chip Resistor"
			(at 82.55 90.17 0)
			(effects
				(font
					(size 1.27 1.27)
				)
				(hide yes)
			)
		)
		(property "MPN" "CR0402-FX-2703GLF"
			(at 62.23 69.85 0)
			(effects
				(font
					(size 1.27 1.27)
					(thickness 0.15)
				)
				(justify left bottom)
				(hide yes)
			)
		)
		(property "Manufacturer" "Bourns"
			(at 59.69 69.85 0)
			(effects
				(font
					(size 1.27 1.27)
					(thickness 0.15)
				)
				(justify left bottom)
				(hide yes)
			)
		)
		(property "License" "Apache-2.0"
			(at 57.15 69.85 0)
			(effects
				(font
					(size 1.27 1.27)
					(thickness 0.15)
				)
				(justify left bottom)
				(hide yes)
			)
		)
		(property "Author" "Antmicro"
			(at 54.61 69.85 0)
			(effects
				(font
					(size 1.27 1.27)
					(thickness 0.15)
				)
				(justify left bottom)
				(hide yes)
			)
		)
		(property "Val" "270k"
			(at 80.01 88.8999 90)
			(effects
				(font
					(size 1.27 1.27)
					(thickness 0.15)
				)
				(justify right)
			)
		)
		(property "Tolerance" "1%"
			(at 72.39 69.85 0)
			(effects
				(font
					(size 1.27 1.27)
				)
				(justify left bottom)
				(hide yes)
			)
		)
		(property "Public" ""
			(at 52.07 69.85 0)
			(effects
				(font
					(size 1.27 1.27)
				)
				(justify left bottom)
				(hide yes)
			)
		)
		(pin "1"
		)
		(pin "2"
		)
		(instances
			(project "polarfire-som"
				(path ""
					(reference "R66")
					(unit 1)
				)
			)
		)
	)
	(symbol
		(lib_id "antmicropower:GND")
		(at 237.49 163.83 0)
		(unit 1)
		(exclude_from_sim no)
		(in_bom yes)
		(on_board yes)
		(dnp no)
		(fields_autoplaced yes)
		(property "Reference" "#PWR0200"
			(at 246.38 166.37 0)
			(effects
				(font
					(size 1.27 1.27)
					(thickness 0.15)
				)
				(justify left bottom)
				(hide yes)
			)
		)
		(property "Value" "GND"
			(at 237.49 168.91 0)
			(effects
				(font
					(size 1.27 1.27)
					(thickness 0.15)
				)
			)
		)
		(property "Footprint" ""
			(at 246.38 171.45 0)
			(effects
				(font
					(size 1.27 1.27)
					(thickness 0.15)
				)
				(justify left bottom)
				(hide yes)
			)
		)
		(property "Datasheet" ""
			(at 246.38 176.53 0)
			(effects
				(font
					(size 1.27 1.27)
					(thickness 0.15)
				)
				(justify left bottom)
				(hide yes)
			)
		)
		(property "Description" ""
			(at 237.49 163.83 0)
			(effects
				(font
					(size 1.27 1.27)
				)
				(hide yes)
			)
		)
		(property "Author" "Antmicro"
			(at 246.38 171.45 0)
			(effects
				(font
					(size 1.27 1.27)
					(thickness 0.15)
				)
				(justify left bottom)
				(hide yes)
			)
		)
		(property "License" "Apache-2.0"
			(at 246.38 173.99 0)
			(effects
				(font
					(size 1.27 1.27)
					(thickness 0.15)
				)
				(justify left bottom)
				(hide yes)
			)
		)
		(pin "1"
		)
		(instances
			(project "polarfire-som"
				(path ""
					(reference "#PWR0200")
					(unit 1)
				)
			)
		)
	)
	(symbol
		(lib_id "antmicropower:+3V3")
		(at 111.76 133.35 0)
		(unit 1)
		(exclude_from_sim no)
		(in_bom yes)
		(on_board yes)
		(dnp no)
		(property "Reference" "#PWR0157"
			(at 127 135.89 0)
			(effects
				(font
					(size 1.27 1.27)
					(thickness 0.15)
				)
				(justify left bottom)
				(hide yes)
			)
		)
		(property "Value" "+3V3"
			(at 111.76 129.54 0)
			(effects
				(font
					(size 1.27 1.27)
					(thickness 0.15)
				)
			)
		)
		(property "Footprint" ""
			(at 127 140.97 0)
			(effects
				(font
					(size 1.27 1.27)
					(thickness 0.15)
				)
				(justify left bottom)
				(hide yes)
			)
		)
		(property "Datasheet" ""
			(at 127 143.51 0)
			(effects
				(font
					(size 1.27 1.27)
					(thickness 0.15)
				)
				(justify left bottom)
				(hide yes)
			)
		)
		(property "Description" ""
			(at 111.76 133.35 0)
			(effects
				(font
					(size 1.27 1.27)
				)
				(hide yes)
			)
		)
		(property "Author" "Antmicro"
			(at 127 140.97 0)
			(effects
				(font
					(size 1.27 1.27)
					(thickness 0.15)
				)
				(justify left bottom)
				(hide yes)
			)
		)
		(property "License" "Apache-2.0"
			(at 127 143.51 0)
			(effects
				(font
					(size 1.27 1.27)
					(thickness 0.15)
				)
				(justify left bottom)
				(hide yes)
			)
		)
		(pin "1"
		)
		(instances
			(project "polarfire-som"
				(path ""
					(reference "#PWR0157")
					(unit 1)
				)
			)
		)
	)
	(symbol
		(lib_id "antmicroTVSDiodes:AXGD10402KR")
		(at 351.79 161.29 90)
		(unit 1)
		(exclude_from_sim no)
		(in_bom yes)
		(on_board yes)
		(dnp no)
		(property "Reference" "D3"
			(at 353.06 158.75 90)
			(effects
				(font
					(size 1.27 1.27)
					(thickness 0.15)
				)
				(justify right)
			)
		)
		(property "Value" "AXGD10402KR"
			(at 361.95 135.89 0)
			(effects
				(font
					(size 1.27 1.27)
					(thickness 0.15)
				)
				(justify left bottom)
				(hide yes)
			)
		)
		(property "Footprint" "antmicro-footprints:D_0402_1005Metric"
			(at 364.49 135.89 0)
			(effects
				(font
					(size 1.27 1.27)
					(thickness 0.15)
				)
				(justify left bottom)
				(hide yes)
			)
		)
		(property "Datasheet" "https://www.littelfuse.com/media?resourcetype=datasheets&itemid=020b2bf2-064c-4ff1-a898-b4ec805b2fea&filename=littelfuse-xtremeguard-axgd-datasheet"
			(at 367.03 135.89 0)
			(effects
				(font
					(size 1.27 1.27)
					(thickness 0.15)
				)
				(justify left bottom)
				(hide yes)
			)
		)
		(property "Description" "Bidirectional TVS, 30 kV,  0402, 24 V, 0.04 pF"
			(at 351.79 161.29 0)
			(effects
				(font
					(size 1.27 1.27)
				)
				(hide yes)
			)
		)
		(property "Manufacturer" "Littelfuse"
			(at 369.57 135.89 0)
			(effects
				(font
					(size 1.27 1.27)
					(thickness 0.15)
				)
				(justify left bottom)
				(hide yes)
			)
		)
		(property "MPN" "AXGD10402KR"
			(at 354.33 160.02 90)
			(effects
				(font
					(size 1.27 1.27)
					(thickness 0.15)
				)
				(justify right)
				(hide yes)
			)
		)
		(property "Author" "Antmicro"
			(at 372.11 135.89 0)
			(effects
				(font
					(size 1.27 1.27)
					(thickness 0.15)
				)
				(justify left bottom)
				(hide yes)
			)
		)
		(property "License" "Apache-2.0"
			(at 374.65 135.89 0)
			(effects
				(font
					(size 1.27 1.27)
					(thickness 0.15)
				)
				(justify left bottom)
				(hide yes)
			)
		)
		(property "Public" ""
			(at 369.57 140.97 0)
			(effects
				(font
					(size 1.27 1.27)
				)
				(justify left bottom)
				(hide yes)
			)
		)
		(pin "1"
		)
		(pin "2"
		)
		(instances
			(project "polarfire-som"
				(path ""
					(reference "D3")
					(unit 1)
				)
			)
		)
	)
	(symbol
		(lib_id "antmicropower:+3V3")
		(at 74.93 177.8 0)
		(mirror y)
		(unit 1)
		(exclude_from_sim no)
		(in_bom yes)
		(on_board yes)
		(dnp no)
		(fields_autoplaced yes)
		(property "Reference" "#PWR0142"
			(at 59.69 180.34 0)
			(effects
				(font
					(size 1.27 1.27)
					(thickness 0.15)
				)
				(justify left bottom)
				(hide yes)
			)
		)
		(property "Value" "+3V3"
			(at 74.93 172.72 0)
			(effects
				(font
					(size 1.27 1.27)
					(thickness 0.15)
				)
			)
		)
		(property "Footprint" ""
			(at 59.69 185.42 0)
			(effects
				(font
					(size 1.27 1.27)
					(thickness 0.15)
				)
				(justify left bottom)
				(hide yes)
			)
		)
		(property "Datasheet" ""
			(at 59.69 187.96 0)
			(effects
				(font
					(size 1.27 1.27)
					(thickness 0.15)
				)
				(justify left bottom)
				(hide yes)
			)
		)
		(property "Description" ""
			(at 74.93 177.8 0)
			(effects
				(font
					(size 1.27 1.27)
				)
				(hide yes)
			)
		)
		(property "Author" "Antmicro"
			(at 59.69 185.42 0)
			(effects
				(font
					(size 1.27 1.27)
					(thickness 0.15)
				)
				(justify left bottom)
				(hide yes)
			)
		)
		(property "License" "Apache-2.0"
			(at 59.69 187.96 0)
			(effects
				(font
					(size 1.27 1.27)
					(thickness 0.15)
				)
				(justify left bottom)
				(hide yes)
			)
		)
		(pin "1"
		)
		(instances
			(project "polarfire-som"
				(path ""
					(reference "#PWR0142")
					(unit 1)
				)
			)
		)
	)
	(symbol
		(lib_id "antmicropower:+3V3")
		(at 251.46 143.51 0)
		(mirror y)
		(unit 1)
		(exclude_from_sim no)
		(in_bom yes)
		(on_board yes)
		(dnp no)
		(property "Reference" "#PWR0205"
			(at 251.46 147.32 0)
			(effects
				(font
					(size 1.27 1.27)
				)
				(hide yes)
			)
		)
		(property "Value" "+3V3"
			(at 251.46 139.7 0)
			(effects
				(font
					(size 1.27 1.27)
				)
			)
		)
		(property "Footprint" ""
			(at 251.46 143.51 0)
			(effects
				(font
					(size 1.27 1.27)
				)
				(hide yes)
			)
		)
		(property "Datasheet" ""
			(at 251.46 143.51 0)
			(effects
				(font
					(size 1.27 1.27)
				)
				(hide yes)
			)
		)
		(property "Description" ""
			(at 251.46 143.51 0)
			(effects
				(font
					(size 1.27 1.27)
				)
				(hide yes)
			)
		)
		(property "Author" "Antmicro"
			(at 236.22 146.05 0)
			(effects
				(font
					(size 1.27 1.27)
					(thickness 0.15)
				)
				(justify left bottom)
				(hide yes)
			)
		)
		(property "License" "Apache-2.0"
			(at 236.22 148.59 0)
			(effects
				(font
					(size 1.27 1.27)
					(thickness 0.15)
				)
				(justify left bottom)
				(hide yes)
			)
		)
		(pin "1"
		)
		(instances
			(project "polarfire-som"
				(path ""
					(reference "#PWR0205")
					(unit 1)
				)
			)
		)
	)
	(symbol
		(lib_id "antmicropower:+1V8")
		(at 129.54 133.35 0)
		(unit 1)
		(exclude_from_sim no)
		(in_bom yes)
		(on_board yes)
		(dnp no)
		(property "Reference" "#PWR0359"
			(at 144.78 135.89 0)
			(effects
				(font
					(size 1.27 1.27)
					(thickness 0.15)
				)
				(justify left bottom)
				(hide yes)
			)
		)
		(property "Value" "+1V8"
			(at 129.54 129.54 0)
			(effects
				(font
					(size 1.27 1.27)
					(thickness 0.15)
				)
			)
		)
		(property "Footprint" ""
			(at 144.78 140.97 0)
			(effects
				(font
					(size 1.27 1.27)
					(thickness 0.15)
				)
				(justify left bottom)
				(hide yes)
			)
		)
		(property "Datasheet" ""
			(at 144.78 143.51 0)
			(effects
				(font
					(size 1.27 1.27)
					(thickness 0.15)
				)
				(justify left bottom)
				(hide yes)
			)
		)
		(property "Description" ""
			(at 129.54 133.35 0)
			(effects
				(font
					(size 1.27 1.27)
				)
				(hide yes)
			)
		)
		(property "Author" "Antmicro"
			(at 144.78 138.43 0)
			(effects
				(font
					(size 1.27 1.27)
					(thickness 0.15)
				)
				(justify left bottom)
				(hide yes)
			)
		)
		(property "License" "Apache-2.0"
			(at 144.78 140.97 0)
			(effects
				(font
					(size 1.27 1.27)
					(thickness 0.15)
				)
				(justify left bottom)
				(hide yes)
			)
		)
		(pin "1"
		)
		(instances
			(project "polarfire-som"
				(path ""
					(reference "#PWR0359")
					(unit 1)
				)
			)
		)
	)
	(symbol
		(lib_id "antmicroCapacitors0402:C_100n_0402")
		(at 67.31 140.97 90)
		(unit 1)
		(exclude_from_sim no)
		(in_bom yes)
		(on_board yes)
		(dnp no)
		(property "Reference" "C185"
			(at 67.31 135.89 90)
			(effects
				(font
					(size 1.27 1.27)
					(thickness 0.15)
				)
				(justify right)
			)
		)
		(property "Value" "C_100n_0402"
			(at 77.47 120.65 0)
			(effects
				(font
					(size 1.27 1.27)
					(thickness 0.15)
				)
				(justify left bottom)
				(hide yes)
			)
		)
		(property "Footprint" "antmicro-footprints:C_0402_1005Metric"
			(at 80.01 120.65 0)
			(effects
				(font
					(size 1.27 1.27)
					(thickness 0.15)
				)
				(justify left bottom)
				(hide yes)
			)
		)
		(property "Datasheet" "https://www.murata.com/products/productdetail?partno=GRM155R61H104KE14%23"
			(at 82.55 120.65 0)
			(effects
				(font
					(size 1.27 1.27)
					(thickness 0.15)
				)
				(justify left bottom)
				(hide yes)
			)
		)
		(property "Description" "SMD Multilayer Ceramic Capacitor, 0.1 µF, 50 V, 0402 [1005 Metric], ± 10%, X5R, GRM Series"
			(at 67.31 140.97 0)
			(effects
				(font
					(size 1.27 1.27)
				)
				(hide yes)
			)
		)
		(property "MPN" "GRM155R61H104KE14D"
			(at 85.09 120.65 0)
			(effects
				(font
					(size 1.27 1.27)
					(thickness 0.15)
				)
				(justify left bottom)
				(hide yes)
			)
		)
		(property "Manufacturer" "Murata"
			(at 87.63 120.65 0)
			(effects
				(font
					(size 1.27 1.27)
					(thickness 0.15)
				)
				(justify left bottom)
				(hide yes)
			)
		)
		(property "License" "Apache-2.0"
			(at 90.17 120.65 0)
			(effects
				(font
					(size 1.27 1.27)
					(thickness 0.15)
				)
				(justify left bottom)
				(hide yes)
			)
		)
		(property "Author" "Antmicro"
			(at 92.71 120.65 0)
			(effects
				(font
					(size 1.27 1.27)
					(thickness 0.15)
				)
				(justify left bottom)
				(hide yes)
			)
		)
		(property "Val" "100n"
			(at 72.39 139.7 90)
			(effects
				(font
					(size 1.27 1.27)
					(thickness 0.15)
				)
				(justify left bottom)
			)
		)
		(property "Voltage" "50V"
			(at 95.25 120.65 0)
			(effects
				(font
					(size 1.27 1.27)
				)
				(justify left bottom)
				(hide yes)
			)
		)
		(property "Dielectric" "X5R"
			(at 97.79 120.65 0)
			(effects
				(font
					(size 1.27 1.27)
				)
				(justify left bottom)
				(hide yes)
			)
		)
		(property "Public" ""
			(at 100.33 120.65 0)
			(effects
				(font
					(size 1.27 1.27)
				)
				(justify left bottom)
				(hide yes)
			)
		)
		(pin "1"
		)
		(pin "2"
		)
		(instances
			(project "polarfire-som"
				(path ""
					(reference "C185")
					(unit 1)
				)
			)
		)
	)
	(symbol
		(lib_id "antmicropower:GND")
		(at 60.96 147.32 0)
		(unit 1)
		(exclude_from_sim no)
		(in_bom yes)
		(on_board yes)
		(dnp no)
		(fields_autoplaced yes)
		(property "Reference" "#PWR0160"
			(at 69.85 149.86 0)
			(effects
				(font
					(size 1.27 1.27)
					(thickness 0.15)
				)
				(justify left bottom)
				(hide yes)
			)
		)
		(property "Value" "GND"
			(at 60.96 152.4 0)
			(effects
				(font
					(size 1.27 1.27)
					(thickness 0.15)
				)
			)
		)
		(property "Footprint" ""
			(at 69.85 154.94 0)
			(effects
				(font
					(size 1.27 1.27)
					(thickness 0.15)
				)
				(justify left bottom)
				(hide yes)
			)
		)
		(property "Datasheet" ""
			(at 69.85 160.02 0)
			(effects
				(font
					(size 1.27 1.27)
					(thickness 0.15)
				)
				(justify left bottom)
				(hide yes)
			)
		)
		(property "Description" ""
			(at 60.96 147.32 0)
			(effects
				(font
					(size 1.27 1.27)
				)
				(hide yes)
			)
		)
		(property "Author" "Antmicro"
			(at 69.85 154.94 0)
			(effects
				(font
					(size 1.27 1.27)
					(thickness 0.15)
				)
				(justify left bottom)
				(hide yes)
			)
		)
		(property "License" "Apache-2.0"
			(at 69.85 157.48 0)
			(effects
				(font
					(size 1.27 1.27)
					(thickness 0.15)
				)
				(justify left bottom)
				(hide yes)
			)
		)
		(pin "1"
		)
		(instances
			(project "polarfire-som"
				(path ""
					(reference "#PWR0160")
					(unit 1)
				)
			)
		)
	)
	(symbol
		(lib_id "antmicropower:+3V3")
		(at 245.11 129.54 0)
		(mirror y)
		(unit 1)
		(exclude_from_sim no)
		(in_bom yes)
		(on_board yes)
		(dnp no)
		(property "Reference" "#PWR0282"
			(at 245.11 133.35 0)
			(effects
				(font
					(size 1.27 1.27)
				)
				(hide yes)
			)
		)
		(property "Value" "+3V3"
			(at 245.11 125.73 0)
			(effects
				(font
					(size 1.27 1.27)
				)
			)
		)
		(property "Footprint" ""
			(at 245.11 129.54 0)
			(effects
				(font
					(size 1.27 1.27)
				)
				(hide yes)
			)
		)
		(property "Datasheet" ""
			(at 245.11 129.54 0)
			(effects
				(font
					(size 1.27 1.27)
				)
				(hide yes)
			)
		)
		(property "Description" ""
			(at 245.11 129.54 0)
			(effects
				(font
					(size 1.27 1.27)
				)
				(hide yes)
			)
		)
		(property "Author" "Antmicro"
			(at 229.87 132.08 0)
			(effects
				(font
					(size 1.27 1.27)
					(thickness 0.15)
				)
				(justify left bottom)
				(hide yes)
			)
		)
		(property "License" "Apache-2.0"
			(at 229.87 134.62 0)
			(effects
				(font
					(size 1.27 1.27)
					(thickness 0.15)
				)
				(justify left bottom)
				(hide yes)
			)
		)
		(pin "1"
		)
		(instances
			(project "polarfire-som"
				(path ""
					(reference "#PWR0282")
					(unit 1)
				)
			)
		)
	)
	(symbol
		(lib_id "antmicropower:+3V3")
		(at 347.98 130.81 0)
		(mirror y)
		(unit 1)
		(exclude_from_sim no)
		(in_bom yes)
		(on_board yes)
		(dnp no)
		(property "Reference" "#PWR0290"
			(at 347.98 134.62 0)
			(effects
				(font
					(size 1.27 1.27)
				)
				(hide yes)
			)
		)
		(property "Value" "+3V3"
			(at 347.98 127 0)
			(effects
				(font
					(size 1.27 1.27)
				)
			)
		)
		(property "Footprint" ""
			(at 347.98 130.81 0)
			(effects
				(font
					(size 1.27 1.27)
				)
				(hide yes)
			)
		)
		(property "Datasheet" ""
			(at 347.98 130.81 0)
			(effects
				(font
					(size 1.27 1.27)
				)
				(hide yes)
			)
		)
		(property "Description" ""
			(at 347.98 130.81 0)
			(effects
				(font
					(size 1.27 1.27)
				)
				(hide yes)
			)
		)
		(property "Author" "Antmicro"
			(at 332.74 133.35 0)
			(effects
				(font
					(size 1.27 1.27)
					(thickness 0.15)
				)
				(justify left bottom)
				(hide yes)
			)
		)
		(property "License" "Apache-2.0"
			(at 332.74 135.89 0)
			(effects
				(font
					(size 1.27 1.27)
					(thickness 0.15)
				)
				(justify left bottom)
				(hide yes)
			)
		)
		(pin "1"
		)
		(instances
			(project "polarfire-som"
				(path ""
					(reference "#PWR0290")
					(unit 1)
				)
			)
		)
	)
	(symbol
		(lib_id "antmicropower:+3V3")
		(at 262.89 92.71 0)
		(mirror y)
		(unit 1)
		(exclude_from_sim no)
		(in_bom yes)
		(on_board yes)
		(dnp no)
		(property "Reference" "#PWR0311"
			(at 262.89 96.52 0)
			(effects
				(font
					(size 1.27 1.27)
				)
				(hide yes)
			)
		)
		(property "Value" "+3V3"
			(at 262.89 88.9 0)
			(effects
				(font
					(size 1.27 1.27)
				)
			)
		)
		(property "Footprint" ""
			(at 262.89 92.71 0)
			(effects
				(font
					(size 1.27 1.27)
				)
				(hide yes)
			)
		)
		(property "Datasheet" ""
			(at 262.89 92.71 0)
			(effects
				(font
					(size 1.27 1.27)
				)
				(hide yes)
			)
		)
		(property "Description" ""
			(at 262.89 92.71 0)
			(effects
				(font
					(size 1.27 1.27)
				)
				(hide yes)
			)
		)
		(property "Author" "Antmicro"
			(at 247.65 95.25 0)
			(effects
				(font
					(size 1.27 1.27)
					(thickness 0.15)
				)
				(justify left bottom)
				(hide yes)
			)
		)
		(property "License" "Apache-2.0"
			(at 247.65 97.79 0)
			(effects
				(font
					(size 1.27 1.27)
					(thickness 0.15)
				)
				(justify left bottom)
				(hide yes)
			)
		)
		(pin "1"
		)
		(instances
			(project "polarfire-som"
				(path ""
					(reference "#PWR0311")
					(unit 1)
				)
			)
		)
	)
	(symbol
		(lib_id "antmicropower:GND")
		(at 125.73 142.24 0)
		(unit 1)
		(exclude_from_sim no)
		(in_bom yes)
		(on_board yes)
		(dnp no)
		(property "Reference" "#PWR0148"
			(at 134.62 144.78 0)
			(effects
				(font
					(size 1.27 1.27)
					(thickness 0.15)
				)
				(justify left bottom)
				(hide yes)
			)
		)
		(property "Value" "GND"
			(at 125.73 146.05 0)
			(effects
				(font
					(size 1.27 1.27)
					(thickness 0.15)
				)
			)
		)
		(property "Footprint" ""
			(at 134.62 149.86 0)
			(effects
				(font
					(size 1.27 1.27)
					(thickness 0.15)
				)
				(justify left bottom)
				(hide yes)
			)
		)
		(property "Datasheet" ""
			(at 134.62 154.94 0)
			(effects
				(font
					(size 1.27 1.27)
					(thickness 0.15)
				)
				(justify left bottom)
				(hide yes)
			)
		)
		(property "Description" ""
			(at 125.73 142.24 0)
			(effects
				(font
					(size 1.27 1.27)
				)
				(hide yes)
			)
		)
		(property "Author" "Antmicro"
			(at 134.62 149.86 0)
			(effects
				(font
					(size 1.27 1.27)
					(thickness 0.15)
				)
				(justify left bottom)
				(hide yes)
			)
		)
		(property "License" "Apache-2.0"
			(at 134.62 152.4 0)
			(effects
				(font
					(size 1.27 1.27)
					(thickness 0.15)
				)
				(justify left bottom)
				(hide yes)
			)
		)
		(pin "1"
		)
		(instances
			(project "polarfire-som"
				(path ""
					(reference "#PWR0148")
					(unit 1)
				)
			)
		)
	)
	(symbol
		(lib_id "antmicroTransistorsFETsMOSFETsSingle:DMG1012T-7")
		(at 144.78 195.58 0)
		(unit 1)
		(exclude_from_sim no)
		(in_bom yes)
		(on_board yes)
		(dnp no)
		(fields_autoplaced yes)
		(property "Reference" "Q4"
			(at 154.94 191.77 0)
			(effects
				(font
					(size 1.27 1.27)
					(thickness 0.15)
				)
				(justify left)
			)
		)
		(property "Value" "DMG1012T-7"
			(at 154.94 199.39 0)
			(effects
				(font
					(size 1.27 1.27)
					(thickness 0.15)
				)
				(justify left bottom)
				(hide yes)
			)
		)
		(property "Footprint" "antmicro-footprints:SOT-523"
			(at 154.94 201.93 0)
			(effects
				(font
					(size 1.27 1.27)
					(thickness 0.15)
				)
				(justify left bottom)
				(hide yes)
			)
		)
		(property "Datasheet" "https://www.diodes.com/assets/Datasheets/ds31783.pdf"
			(at 154.94 204.47 0)
			(effects
				(font
					(size 1.27 1.27)
					(thickness 0.15)
				)
				(justify left bottom)
				(hide yes)
			)
		)
		(property "Description" "Power MOSFET, N Channel, 20 V, 630 mA, 0.3 ohm, SOT-523, Surface Mount"
			(at 144.78 195.58 0)
			(effects
				(font
					(size 1.27 1.27)
				)
				(hide yes)
			)
		)
		(property "MPN" "DMG1012T-7"
			(at 154.94 194.31 0)
			(effects
				(font
					(size 1.27 1.27)
					(thickness 0.15)
				)
				(justify left)
			)
		)
		(property "Manufacturer" "Diodes Incorporated"
			(at 154.94 196.85 0)
			(effects
				(font
					(size 1.27 1.27)
					(thickness 0.15)
				)
				(justify left bottom)
				(hide yes)
			)
		)
		(property "Author" "Antmicro"
			(at 154.94 207.01 0)
			(effects
				(font
					(size 1.27 1.27)
					(thickness 0.15)
				)
				(justify left bottom)
				(hide yes)
			)
		)
		(property "License" "Apache-2.0"
			(at 154.94 209.55 0)
			(effects
				(font
					(size 1.27 1.27)
					(thickness 0.15)
				)
				(justify left bottom)
				(hide yes)
			)
		)
		(property "Public" ""
			(at 165.1 203.2 0)
			(effects
				(font
					(size 1.27 1.27)
				)
				(justify left bottom)
				(hide yes)
			)
		)
		(pin "1"
		)
		(pin "2"
		)
		(pin "3"
		)
		(instances
			(project "polarfire-som"
				(path ""
					(reference "Q4")
					(unit 1)
				)
			)
		)
	)
	(symbol
		(lib_id "antmicropower:GND")
		(at 349.25 166.37 0)
		(unit 1)
		(exclude_from_sim no)
		(in_bom yes)
		(on_board yes)
		(dnp no)
		(fields_autoplaced yes)
		(property "Reference" "#PWR0119"
			(at 358.14 168.91 0)
			(effects
				(font
					(size 1.27 1.27)
					(thickness 0.15)
				)
				(justify left bottom)
				(hide yes)
			)
		)
		(property "Value" "GND"
			(at 349.25 171.45 0)
			(effects
				(font
					(size 1.27 1.27)
					(thickness 0.15)
				)
			)
		)
		(property "Footprint" ""
			(at 358.14 173.99 0)
			(effects
				(font
					(size 1.27 1.27)
					(thickness 0.15)
				)
				(justify left bottom)
				(hide yes)
			)
		)
		(property "Datasheet" ""
			(at 358.14 179.07 0)
			(effects
				(font
					(size 1.27 1.27)
					(thickness 0.15)
				)
				(justify left bottom)
				(hide yes)
			)
		)
		(property "Description" ""
			(at 349.25 166.37 0)
			(effects
				(font
					(size 1.27 1.27)
				)
				(hide yes)
			)
		)
		(property "Author" "Antmicro"
			(at 358.14 173.99 0)
			(effects
				(font
					(size 1.27 1.27)
					(thickness 0.15)
				)
				(justify left bottom)
				(hide yes)
			)
		)
		(property "License" "Apache-2.0"
			(at 358.14 176.53 0)
			(effects
				(font
					(size 1.27 1.27)
					(thickness 0.15)
				)
				(justify left bottom)
				(hide yes)
			)
		)
		(pin "1"
		)
		(instances
			(project "polarfire-som"
				(path ""
					(reference "#PWR0119")
					(unit 1)
				)
			)
		)
	)
	(symbol
		(lib_id "antmicroResistors0402:R_27R_0402")
		(at 90.17 92.71 0)
		(unit 1)
		(exclude_from_sim no)
		(in_bom yes)
		(on_board yes)
		(dnp no)
		(property "Reference" "R65"
			(at 87.63 91.44 0)
			(effects
				(font
					(size 1.27 1.27)
					(thickness 0.15)
				)
			)
		)
		(property "Value" "R_27R_0402"
			(at 110.49 105.41 0)
			(effects
				(font
					(size 1.27 1.27)
					(thickness 0.15)
				)
				(justify left bottom)
				(hide yes)
			)
		)
		(property "Footprint" "antmicro-footprints:R_0402_1005Metric"
			(at 110.49 107.95 0)
			(effects
				(font
					(size 1.27 1.27)
					(thickness 0.15)
				)
				(justify left bottom)
				(hide yes)
			)
		)
		(property "Datasheet" "https://www.bourns.com/docs/product-datasheets/cr.pdf"
			(at 110.49 110.49 0)
			(effects
				(font
					(size 1.27 1.27)
					(thickness 0.15)
				)
				(justify left bottom)
				(hide yes)
			)
		)
		(property "Description" "SMD Chip Resistor, 27 ohm, ± 1%, 63 mW, 0402 [1005 Metric], Thick Film, General Purpose"
			(at 90.17 92.71 0)
			(effects
				(font
					(size 1.27 1.27)
				)
				(hide yes)
			)
		)
		(property "MPN" "CR0402-FX-27R0GLF"
			(at 110.49 113.03 0)
			(effects
				(font
					(size 1.27 1.27)
					(thickness 0.15)
				)
				(justify left bottom)
				(hide yes)
			)
		)
		(property "Manufacturer" "Bourns"
			(at 110.49 115.57 0)
			(effects
				(font
					(size 1.27 1.27)
					(thickness 0.15)
				)
				(justify left bottom)
				(hide yes)
			)
		)
		(property "License" "Apache-2.0"
			(at 110.49 118.11 0)
			(effects
				(font
					(size 1.27 1.27)
					(thickness 0.15)
				)
				(justify left bottom)
				(hide yes)
			)
		)
		(property "Author" "Antmicro"
			(at 110.49 120.65 0)
			(effects
				(font
					(size 1.27 1.27)
					(thickness 0.15)
				)
				(justify left bottom)
				(hide yes)
			)
		)
		(property "Val" "27R"
			(at 97.79 91.44 0)
			(effects
				(font
					(size 1.27 1.27)
					(thickness 0.15)
				)
			)
		)
		(property "Tolerance" "1%"
			(at 110.49 102.87 0)
			(effects
				(font
					(size 1.27 1.27)
				)
				(justify left bottom)
				(hide yes)
			)
		)
		(property "Public" ""
			(at 110.49 123.19 0)
			(effects
				(font
					(size 1.27 1.27)
				)
				(justify left bottom)
				(hide yes)
			)
		)
		(pin "2"
		)
		(pin "1"
		)
		(instances
			(project "polarfire-som"
				(path ""
					(reference "R65")
					(unit 1)
				)
			)
		)
	)
	(symbol
		(lib_id "antmicroTestPoints:TP_0.75mm_SMD")
		(at 140.97 81.28 0)
		(unit 1)
		(exclude_from_sim no)
		(in_bom no)
		(on_board yes)
		(dnp no)
		(fields_autoplaced yes)
		(property "Reference" "TP10"
			(at 146.05 81.2799 0)
			(effects
				(font
					(size 1.27 1.27)
					(thickness 0.15)
				)
				(justify left)
			)
		)
		(property "Value" "TP_0.75mm_SMD"
			(at 151.765 85.09 0)
			(effects
				(font
					(size 1.27 1.27)
					(thickness 0.15)
				)
				(justify left bottom)
				(hide yes)
			)
		)
		(property "Footprint" "antmicro-footprints:TP_SMD_0.75mm"
			(at 151.765 87.63 0)
			(effects
				(font
					(size 1.27 1.27)
					(thickness 0.15)
				)
				(justify left bottom)
				(hide yes)
			)
		)
		(property "Datasheet" ""
			(at 158.75 93.98 0)
			(effects
				(font
					(size 1.27 1.27)
					(thickness 0.15)
				)
				(justify left bottom)
				(hide yes)
			)
		)
		(property "Description" "SMT test point"
			(at 140.97 81.28 0)
			(effects
				(font
					(size 1.27 1.27)
				)
				(hide yes)
			)
		)
		(property "MPN" ""
			(at 151.765 92.71 0)
			(effects
				(font
					(size 1.27 1.27)
					(thickness 0.15)
				)
				(justify left bottom)
				(hide yes)
			)
		)
		(property "Manufacturer" ""
			(at 151.765 87.63 0)
			(effects
				(font
					(size 1.27 1.27)
					(thickness 0.15)
				)
				(justify left bottom)
				(hide yes)
			)
		)
		(property "Author" "Antmicro"
			(at 151.765 90.17 0)
			(effects
				(font
					(size 1.27 1.27)
					(thickness 0.15)
				)
				(justify left bottom)
				(hide yes)
			)
		)
		(property "License" "Apache-2.0"
			(at 151.765 92.71 0)
			(effects
				(font
					(size 1.27 1.27)
					(thickness 0.15)
				)
				(justify left bottom)
				(hide yes)
			)
		)
		(property "Public" "False"
			(at 151.13 95.25 0)
			(effects
				(font
					(size 1.27 1.27)
				)
				(justify left bottom)
				(hide yes)
			)
		)
		(pin "1"
		)
		(instances
			(project "polarfire-som"
				(path ""
					(reference "TP10")
					(unit 1)
				)
			)
		)
	)
	(symbol
		(lib_id "antmicropower:GND")
		(at 160.02 57.15 0)
		(unit 1)
		(exclude_from_sim no)
		(in_bom yes)
		(on_board yes)
		(dnp no)
		(property "Reference" "#PWR0209"
			(at 168.91 59.69 0)
			(effects
				(font
					(size 1.27 1.27)
					(thickness 0.15)
				)
				(justify left bottom)
				(hide yes)
			)
		)
		(property "Value" "GND"
			(at 160.02 60.96 0)
			(effects
				(font
					(size 1.27 1.27)
					(thickness 0.15)
				)
			)
		)
		(property "Footprint" ""
			(at 168.91 64.77 0)
			(effects
				(font
					(size 1.27 1.27)
					(thickness 0.15)
				)
				(justify left bottom)
				(hide yes)
			)
		)
		(property "Datasheet" ""
			(at 168.91 69.85 0)
			(effects
				(font
					(size 1.27 1.27)
					(thickness 0.15)
				)
				(justify left bottom)
				(hide yes)
			)
		)
		(property "Description" ""
			(at 160.02 57.15 0)
			(effects
				(font
					(size 1.27 1.27)
				)
				(hide yes)
			)
		)
		(property "Author" "Antmicro"
			(at 168.91 64.77 0)
			(effects
				(font
					(size 1.27 1.27)
					(thickness 0.15)
				)
				(justify left bottom)
				(hide yes)
			)
		)
		(property "License" "Apache-2.0"
			(at 168.91 67.31 0)
			(effects
				(font
					(size 1.27 1.27)
					(thickness 0.15)
				)
				(justify left bottom)
				(hide yes)
			)
		)
		(pin "1"
		)
		(instances
			(project "polarfire-som"
				(path ""
					(reference "#PWR0209")
					(unit 1)
				)
			)
		)
	)
	(symbol
		(lib_id "antmicroResistors0402:R_10k_0402")
		(at 139.7 190.5 90)
		(unit 1)
		(exclude_from_sim no)
		(in_bom yes)
		(on_board yes)
		(dnp no)
		(property "Reference" "R86"
			(at 142.24 186.69 90)
			(effects
				(font
					(size 1.27 1.27)
					(thickness 0.15)
				)
				(justify right)
			)
		)
		(property "Value" "R_10k_0402"
			(at 152.4 170.18 0)
			(effects
				(font
					(size 1.27 1.27)
					(thickness 0.15)
				)
				(justify left bottom)
				(hide yes)
			)
		)
		(property "Footprint" "antmicro-footprints:R_0402_1005Metric"
			(at 154.94 170.18 0)
			(effects
				(font
					(size 1.27 1.27)
					(thickness 0.15)
				)
				(justify left bottom)
				(hide yes)
			)
		)
		(property "Datasheet" "https://www.bourns.com/docs/product-datasheets/cr.pdf"
			(at 157.48 170.18 0)
			(effects
				(font
					(size 1.27 1.27)
					(thickness 0.15)
				)
				(justify left bottom)
				(hide yes)
			)
		)
		(property "Description" "SMD Chip Resistor, 10 kohm, ± 1%, 62.5 mW, 0402 [1005 Metric], Thick Film, General Purpose"
			(at 139.7 190.5 0)
			(effects
				(font
					(size 1.27 1.27)
				)
				(hide yes)
			)
		)
		(property "MPN" "CR0402-FX-1002GLF"
			(at 160.02 170.18 0)
			(effects
				(font
					(size 1.27 1.27)
					(thickness 0.15)
				)
				(justify left bottom)
				(hide yes)
			)
		)
		(property "Manufacturer" "Bourns"
			(at 162.56 170.18 0)
			(effects
				(font
					(size 1.27 1.27)
					(thickness 0.15)
				)
				(justify left bottom)
				(hide yes)
			)
		)
		(property "License" "Apache-2.0"
			(at 165.1 170.18 0)
			(effects
				(font
					(size 1.27 1.27)
					(thickness 0.15)
				)
				(justify left bottom)
				(hide yes)
			)
		)
		(property "Author" "Antmicro"
			(at 167.64 170.18 0)
			(effects
				(font
					(size 1.27 1.27)
					(thickness 0.15)
				)
				(justify left bottom)
				(hide yes)
			)
		)
		(property "Val" "10k"
			(at 142.24 189.23 90)
			(effects
				(font
					(size 1.27 1.27)
					(thickness 0.15)
				)
				(justify right)
			)
		)
		(property "Tolerance" "1%"
			(at 149.86 170.18 0)
			(effects
				(font
					(size 1.27 1.27)
				)
				(justify left bottom)
				(hide yes)
			)
		)
		(property "Public" ""
			(at 170.18 170.18 0)
			(effects
				(font
					(size 1.27 1.27)
				)
				(justify left bottom)
				(hide yes)
			)
		)
		(pin "1"
		)
		(pin "2"
		)
		(instances
			(project "polarfire-som"
				(path ""
					(reference "R86")
					(unit 1)
				)
			)
		)
	)
	(symbol
		(lib_id "antmicroCapacitors0402:C_100n_0402")
		(at 345.44 71.12 90)
		(unit 1)
		(exclude_from_sim no)
		(in_bom yes)
		(on_board yes)
		(dnp no)
		(property "Reference" "C221"
			(at 346.71 67.31 90)
			(effects
				(font
					(size 1.27 1.27)
					(thickness 0.15)
				)
				(justify right)
			)
		)
		(property "Value" "C_100n_0402"
			(at 355.6 50.8 0)
			(effects
				(font
					(size 1.27 1.27)
					(thickness 0.15)
				)
				(justify left bottom)
				(hide yes)
			)
		)
		(property "Footprint" "antmicro-footprints:C_0402_1005Metric"
			(at 358.14 50.8 0)
			(effects
				(font
					(size 1.27 1.27)
					(thickness 0.15)
				)
				(justify left bottom)
				(hide yes)
			)
		)
		(property "Datasheet" "https://www.murata.com/products/productdetail?partno=GRM155R61H104KE14%23"
			(at 360.68 50.8 0)
			(effects
				(font
					(size 1.27 1.27)
					(thickness 0.15)
				)
				(justify left bottom)
				(hide yes)
			)
		)
		(property "Description" "SMD Multilayer Ceramic Capacitor, 0.1 µF, 50 V, 0402 [1005 Metric], ± 10%, X5R, GRM Series"
			(at 345.44 71.12 0)
			(effects
				(font
					(size 1.27 1.27)
				)
				(hide yes)
			)
		)
		(property "MPN" "GRM155R61H104KE14D"
			(at 363.22 50.8 0)
			(effects
				(font
					(size 1.27 1.27)
					(thickness 0.15)
				)
				(justify left bottom)
				(hide yes)
			)
		)
		(property "Manufacturer" "Murata"
			(at 365.76 50.8 0)
			(effects
				(font
					(size 1.27 1.27)
					(thickness 0.15)
				)
				(justify left bottom)
				(hide yes)
			)
		)
		(property "License" "Apache-2.0"
			(at 368.3 50.8 0)
			(effects
				(font
					(size 1.27 1.27)
					(thickness 0.15)
				)
				(justify left bottom)
				(hide yes)
			)
		)
		(property "Author" "Antmicro"
			(at 370.84 50.8 0)
			(effects
				(font
					(size 1.27 1.27)
					(thickness 0.15)
				)
				(justify left bottom)
				(hide yes)
			)
		)
		(property "Val" "100n"
			(at 351.79 69.85 90)
			(effects
				(font
					(size 1.27 1.27)
					(thickness 0.15)
				)
				(justify left bottom)
			)
		)
		(property "Voltage" "50V"
			(at 373.38 50.8 0)
			(effects
				(font
					(size 1.27 1.27)
				)
				(justify left bottom)
				(hide yes)
			)
		)
		(property "Dielectric" "X5R"
			(at 375.92 50.8 0)
			(effects
				(font
					(size 1.27 1.27)
				)
				(justify left bottom)
				(hide yes)
			)
		)
		(property "Public" ""
			(at 378.46 50.8 0)
			(effects
				(font
					(size 1.27 1.27)
				)
				(justify left bottom)
				(hide yes)
			)
		)
		(pin "1"
		)
		(pin "2"
		)
		(instances
			(project "polarfire-som"
				(path ""
					(reference "C221")
					(unit 1)
				)
			)
		)
	)
	(symbol
		(lib_id "antmicropower:VDDI")
		(at 88.9 132.08 0)
		(unit 1)
		(exclude_from_sim no)
		(in_bom yes)
		(on_board yes)
		(dnp no)
		(fields_autoplaced yes)
		(property "Reference" "#PWR0338"
			(at 88.9 135.89 0)
			(effects
				(font
					(size 1.27 1.27)
				)
				(hide yes)
			)
		)
		(property "Value" "VDD"
			(at 88.9 127.635 0)
			(effects
				(font
					(size 1.27 1.27)
				)
			)
		)
		(property "Footprint" ""
			(at 88.9 132.08 0)
			(effects
				(font
					(size 1.27 1.27)
				)
				(hide yes)
			)
		)
		(property "Datasheet" ""
			(at 88.9 132.08 0)
			(effects
				(font
					(size 1.27 1.27)
				)
				(hide yes)
			)
		)
		(property "Description" ""
			(at 88.9 132.08 0)
			(effects
				(font
					(size 1.27 1.27)
				)
				(hide yes)
			)
		)
		(pin "1"
		)
		(instances
			(project "polarfire-som"
				(path ""
					(reference "#PWR0338")
					(unit 1)
				)
			)
		)
	)
	(symbol
		(lib_id "antmicroCapacitors0402:C_100n_0402")
		(at 354.33 71.12 90)
		(unit 1)
		(exclude_from_sim no)
		(in_bom yes)
		(on_board yes)
		(dnp no)
		(property "Reference" "C222"
			(at 355.6 67.31 90)
			(effects
				(font
					(size 1.27 1.27)
					(thickness 0.15)
				)
				(justify right)
			)
		)
		(property "Value" "C_100n_0402"
			(at 364.49 50.8 0)
			(effects
				(font
					(size 1.27 1.27)
					(thickness 0.15)
				)
				(justify left bottom)
				(hide yes)
			)
		)
		(property "Footprint" "antmicro-footprints:C_0402_1005Metric"
			(at 367.03 50.8 0)
			(effects
				(font
					(size 1.27 1.27)
					(thickness 0.15)
				)
				(justify left bottom)
				(hide yes)
			)
		)
		(property "Datasheet" "https://www.murata.com/products/productdetail?partno=GRM155R61H104KE14%23"
			(at 369.57 50.8 0)
			(effects
				(font
					(size 1.27 1.27)
					(thickness 0.15)
				)
				(justify left bottom)
				(hide yes)
			)
		)
		(property "Description" "SMD Multilayer Ceramic Capacitor, 0.1 µF, 50 V, 0402 [1005 Metric], ± 10%, X5R, GRM Series"
			(at 354.33 71.12 0)
			(effects
				(font
					(size 1.27 1.27)
				)
				(hide yes)
			)
		)
		(property "MPN" "GRM155R61H104KE14D"
			(at 372.11 50.8 0)
			(effects
				(font
					(size 1.27 1.27)
					(thickness 0.15)
				)
				(justify left bottom)
				(hide yes)
			)
		)
		(property "Manufacturer" "Murata"
			(at 374.65 50.8 0)
			(effects
				(font
					(size 1.27 1.27)
					(thickness 0.15)
				)
				(justify left bottom)
				(hide yes)
			)
		)
		(property "License" "Apache-2.0"
			(at 377.19 50.8 0)
			(effects
				(font
					(size 1.27 1.27)
					(thickness 0.15)
				)
				(justify left bottom)
				(hide yes)
			)
		)
		(property "Author" "Antmicro"
			(at 379.73 50.8 0)
			(effects
				(font
					(size 1.27 1.27)
					(thickness 0.15)
				)
				(justify left bottom)
				(hide yes)
			)
		)
		(property "Val" "100n"
			(at 360.68 69.85 90)
			(effects
				(font
					(size 1.27 1.27)
					(thickness 0.15)
				)
				(justify left bottom)
			)
		)
		(property "Voltage" "50V"
			(at 382.27 50.8 0)
			(effects
				(font
					(size 1.27 1.27)
				)
				(justify left bottom)
				(hide yes)
			)
		)
		(property "Dielectric" "X5R"
			(at 384.81 50.8 0)
			(effects
				(font
					(size 1.27 1.27)
				)
				(justify left bottom)
				(hide yes)
			)
		)
		(property "Public" ""
			(at 387.35 50.8 0)
			(effects
				(font
					(size 1.27 1.27)
				)
				(justify left bottom)
				(hide yes)
			)
		)
		(pin "1"
		)
		(pin "2"
		)
		(instances
			(project "polarfire-som"
				(path ""
					(reference "C222")
					(unit 1)
				)
			)
		)
	)
	(symbol
		(lib_id "antmicroTVSDiodes:AXGD10402KR")
		(at 346.71 161.29 90)
		(unit 1)
		(exclude_from_sim no)
		(in_bom yes)
		(on_board yes)
		(dnp no)
		(property "Reference" "D2"
			(at 342.9 158.75 90)
			(effects
				(font
					(size 1.27 1.27)
					(thickness 0.15)
				)
				(justify right)
			)
		)
		(property "Value" "AXGD10402KR"
			(at 356.87 135.89 0)
			(effects
				(font
					(size 1.27 1.27)
					(thickness 0.15)
				)
				(justify left bottom)
				(hide yes)
			)
		)
		(property "Footprint" "antmicro-footprints:D_0402_1005Metric"
			(at 359.41 135.89 0)
			(effects
				(font
					(size 1.27 1.27)
					(thickness 0.15)
				)
				(justify left bottom)
				(hide yes)
			)
		)
		(property "Datasheet" "https://www.littelfuse.com/media?resourcetype=datasheets&itemid=020b2bf2-064c-4ff1-a898-b4ec805b2fea&filename=littelfuse-xtremeguard-axgd-datasheet"
			(at 361.95 135.89 0)
			(effects
				(font
					(size 1.27 1.27)
					(thickness 0.15)
				)
				(justify left bottom)
				(hide yes)
			)
		)
		(property "Description" "Bidirectional TVS, 30 kV,  0402, 24 V, 0.04 pF"
			(at 346.71 161.29 0)
			(effects
				(font
					(size 1.27 1.27)
				)
				(hide yes)
			)
		)
		(property "Manufacturer" "Littelfuse"
			(at 364.49 135.89 0)
			(effects
				(font
					(size 1.27 1.27)
					(thickness 0.15)
				)
				(justify left bottom)
				(hide yes)
			)
		)
		(property "MPN" "AXGD10402KR"
			(at 349.25 160.02 90)
			(effects
				(font
					(size 1.27 1.27)
					(thickness 0.15)
				)
				(justify right)
				(hide yes)
			)
		)
		(property "Author" "Antmicro"
			(at 367.03 135.89 0)
			(effects
				(font
					(size 1.27 1.27)
					(thickness 0.15)
				)
				(justify left bottom)
				(hide yes)
			)
		)
		(property "License" "Apache-2.0"
			(at 369.57 135.89 0)
			(effects
				(font
					(size 1.27 1.27)
					(thickness 0.15)
				)
				(justify left bottom)
				(hide yes)
			)
		)
		(property "Public" ""
			(at 364.49 140.97 0)
			(effects
				(font
					(size 1.27 1.27)
				)
				(justify left bottom)
				(hide yes)
			)
		)
		(pin "1"
		)
		(pin "2"
		)
		(instances
			(project "polarfire-som"
				(path ""
					(reference "D2")
					(unit 1)
				)
			)
		)
	)
	(symbol
		(lib_id "antmicropower:GND")
		(at 347.98 138.43 0)
		(unit 1)
		(exclude_from_sim no)
		(in_bom yes)
		(on_board yes)
		(dnp no)
		(fields_autoplaced yes)
		(property "Reference" "#PWR0121"
			(at 356.87 140.97 0)
			(effects
				(font
					(size 1.27 1.27)
					(thickness 0.15)
				)
				(justify left bottom)
				(hide yes)
			)
		)
		(property "Value" "GND"
			(at 347.98 143.51 0)
			(effects
				(font
					(size 1.27 1.27)
					(thickness 0.15)
				)
			)
		)
		(property "Footprint" ""
			(at 356.87 146.05 0)
			(effects
				(font
					(size 1.27 1.27)
					(thickness 0.15)
				)
				(justify left bottom)
				(hide yes)
			)
		)
		(property "Datasheet" ""
			(at 356.87 151.13 0)
			(effects
				(font
					(size 1.27 1.27)
					(thickness 0.15)
				)
				(justify left bottom)
				(hide yes)
			)
		)
		(property "Description" ""
			(at 347.98 138.43 0)
			(effects
				(font
					(size 1.27 1.27)
				)
				(hide yes)
			)
		)
		(property "Author" "Antmicro"
			(at 356.87 146.05 0)
			(effects
				(font
					(size 1.27 1.27)
					(thickness 0.15)
				)
				(justify left bottom)
				(hide yes)
			)
		)
		(property "License" "Apache-2.0"
			(at 356.87 148.59 0)
			(effects
				(font
					(size 1.27 1.27)
					(thickness 0.15)
				)
				(justify left bottom)
				(hide yes)
			)
		)
		(pin "1"
		)
		(instances
			(project "polarfire-som"
				(path ""
					(reference "#PWR0121")
					(unit 1)
				)
			)
		)
	)
	(symbol
		(lib_id "antmicropower:+3V3")
		(at 345.44 62.23 0)
		(mirror y)
		(unit 1)
		(exclude_from_sim no)
		(in_bom yes)
		(on_board yes)
		(dnp no)
		(property "Reference" "#PWR0280"
			(at 345.44 66.04 0)
			(effects
				(font
					(size 1.27 1.27)
				)
				(hide yes)
			)
		)
		(property "Value" "+3V3"
			(at 345.44 58.42 0)
			(effects
				(font
					(size 1.27 1.27)
				)
			)
		)
		(property "Footprint" ""
			(at 345.44 62.23 0)
			(effects
				(font
					(size 1.27 1.27)
				)
				(hide yes)
			)
		)
		(property "Datasheet" ""
			(at 345.44 62.23 0)
			(effects
				(font
					(size 1.27 1.27)
				)
				(hide yes)
			)
		)
		(property "Description" ""
			(at 345.44 62.23 0)
			(effects
				(font
					(size 1.27 1.27)
				)
				(hide yes)
			)
		)
		(property "Author" "Antmicro"
			(at 330.2 64.77 0)
			(effects
				(font
					(size 1.27 1.27)
					(thickness 0.15)
				)
				(justify left bottom)
				(hide yes)
			)
		)
		(property "License" "Apache-2.0"
			(at 330.2 67.31 0)
			(effects
				(font
					(size 1.27 1.27)
					(thickness 0.15)
				)
				(justify left bottom)
				(hide yes)
			)
		)
		(pin "1"
		)
		(instances
			(project "polarfire-som"
				(path ""
					(reference "#PWR0280")
					(unit 1)
				)
			)
		)
	)
	(symbol
		(lib_id "antmicropower:GND")
		(at 161.29 142.24 0)
		(unit 1)
		(exclude_from_sim no)
		(in_bom yes)
		(on_board yes)
		(dnp no)
		(fields_autoplaced yes)
		(property "Reference" "#PWR0149"
			(at 170.18 144.78 0)
			(effects
				(font
					(size 1.27 1.27)
					(thickness 0.15)
				)
				(justify left bottom)
				(hide yes)
			)
		)
		(property "Value" "GND"
			(at 161.29 147.32 0)
			(effects
				(font
					(size 1.27 1.27)
					(thickness 0.15)
				)
			)
		)
		(property "Footprint" ""
			(at 170.18 149.86 0)
			(effects
				(font
					(size 1.27 1.27)
					(thickness 0.15)
				)
				(justify left bottom)
				(hide yes)
			)
		)
		(property "Datasheet" ""
			(at 170.18 154.94 0)
			(effects
				(font
					(size 1.27 1.27)
					(thickness 0.15)
				)
				(justify left bottom)
				(hide yes)
			)
		)
		(property "Description" ""
			(at 161.29 142.24 0)
			(effects
				(font
					(size 1.27 1.27)
				)
				(hide yes)
			)
		)
		(property "Author" "Antmicro"
			(at 170.18 149.86 0)
			(effects
				(font
					(size 1.27 1.27)
					(thickness 0.15)
				)
				(justify left bottom)
				(hide yes)
			)
		)
		(property "License" "Apache-2.0"
			(at 170.18 152.4 0)
			(effects
				(font
					(size 1.27 1.27)
					(thickness 0.15)
				)
				(justify left bottom)
				(hide yes)
			)
		)
		(pin "1"
		)
		(instances
			(project "polarfire-som"
				(path ""
					(reference "#PWR0149")
					(unit 1)
				)
			)
		)
	)
	(symbol
		(lib_id "antmicroResistors0402:R_10k_0402")
		(at 151.13 185.42 90)
		(unit 1)
		(exclude_from_sim no)
		(in_bom yes)
		(on_board yes)
		(dnp no)
		(property "Reference" "R85"
			(at 153.67 181.61 90)
			(effects
				(font
					(size 1.27 1.27)
					(thickness 0.15)
				)
				(justify right)
			)
		)
		(property "Value" "R_10k_0402"
			(at 163.83 165.1 0)
			(effects
				(font
					(size 1.27 1.27)
					(thickness 0.15)
				)
				(justify left bottom)
				(hide yes)
			)
		)
		(property "Footprint" "antmicro-footprints:R_0402_1005Metric"
			(at 166.37 165.1 0)
			(effects
				(font
					(size 1.27 1.27)
					(thickness 0.15)
				)
				(justify left bottom)
				(hide yes)
			)
		)
		(property "Datasheet" "https://www.bourns.com/docs/product-datasheets/cr.pdf"
			(at 168.91 165.1 0)
			(effects
				(font
					(size 1.27 1.27)
					(thickness 0.15)
				)
				(justify left bottom)
				(hide yes)
			)
		)
		(property "Description" "SMD Chip Resistor, 10 kohm, ± 1%, 62.5 mW, 0402 [1005 Metric], Thick Film, General Purpose"
			(at 151.13 185.42 0)
			(effects
				(font
					(size 1.27 1.27)
				)
				(hide yes)
			)
		)
		(property "MPN" "CR0402-FX-1002GLF"
			(at 171.45 165.1 0)
			(effects
				(font
					(size 1.27 1.27)
					(thickness 0.15)
				)
				(justify left bottom)
				(hide yes)
			)
		)
		(property "Manufacturer" "Bourns"
			(at 173.99 165.1 0)
			(effects
				(font
					(size 1.27 1.27)
					(thickness 0.15)
				)
				(justify left bottom)
				(hide yes)
			)
		)
		(property "License" "Apache-2.0"
			(at 176.53 165.1 0)
			(effects
				(font
					(size 1.27 1.27)
					(thickness 0.15)
				)
				(justify left bottom)
				(hide yes)
			)
		)
		(property "Author" "Antmicro"
			(at 179.07 165.1 0)
			(effects
				(font
					(size 1.27 1.27)
					(thickness 0.15)
				)
				(justify left bottom)
				(hide yes)
			)
		)
		(property "Val" "10k"
			(at 153.67 184.15 90)
			(effects
				(font
					(size 1.27 1.27)
					(thickness 0.15)
				)
				(justify right)
			)
		)
		(property "Tolerance" "1%"
			(at 161.29 165.1 0)
			(effects
				(font
					(size 1.27 1.27)
				)
				(justify left bottom)
				(hide yes)
			)
		)
		(property "Public" ""
			(at 181.61 165.1 0)
			(effects
				(font
					(size 1.27 1.27)
				)
				(justify left bottom)
				(hide yes)
			)
		)
		(pin "1"
		)
		(pin "2"
		)
		(instances
			(project "polarfire-som"
				(path ""
					(reference "R85")
					(unit 1)
				)
			)
		)
	)
	(symbol
		(lib_id "antmicroResistors0402:R_12k_0402")
		(at 313.69 102.87 90)
		(unit 1)
		(exclude_from_sim no)
		(in_bom yes)
		(on_board yes)
		(dnp no)
		(property "Reference" "R166"
			(at 314.96 99.06 90)
			(effects
				(font
					(size 1.27 1.27)
					(thickness 0.15)
				)
				(justify right)
			)
		)
		(property "Value" "R_12k_0402"
			(at 326.39 82.55 0)
			(effects
				(font
					(size 1.27 1.27)
					(thickness 0.15)
				)
				(justify left bottom)
				(hide yes)
			)
		)
		(property "Footprint" "antmicro-footprints:R_0402_1005Metric"
			(at 328.93 82.55 0)
			(effects
				(font
					(size 1.27 1.27)
					(thickness 0.15)
				)
				(justify left bottom)
				(hide yes)
			)
		)
		(property "Datasheet" "https://www.bourns.com/docs/product-datasheets/cr.pdf"
			(at 331.47 82.55 0)
			(effects
				(font
					(size 1.27 1.27)
					(thickness 0.15)
				)
				(justify left bottom)
				(hide yes)
			)
		)
		(property "Description" "SMD Chip Resistor, 12 kohm, ± 1%, 62.5 mW, 0402 [1005 Metric], Thick Film, General Purpose"
			(at 313.69 102.87 0)
			(effects
				(font
					(size 1.27 1.27)
				)
				(hide yes)
			)
		)
		(property "MPN" "CR0402-FX-1202GLF"
			(at 334.01 82.55 0)
			(effects
				(font
					(size 1.27 1.27)
					(thickness 0.15)
				)
				(justify left bottom)
				(hide yes)
			)
		)
		(property "Manufacturer" "Bourns"
			(at 336.55 82.55 0)
			(effects
				(font
					(size 1.27 1.27)
					(thickness 0.15)
				)
				(justify left bottom)
				(hide yes)
			)
		)
		(property "License" "Apache-2.0"
			(at 339.09 82.55 0)
			(effects
				(font
					(size 1.27 1.27)
					(thickness 0.15)
				)
				(justify left bottom)
				(hide yes)
			)
		)
		(property "Author" "Antmicro"
			(at 341.63 82.55 0)
			(effects
				(font
					(size 1.27 1.27)
					(thickness 0.15)
				)
				(justify left bottom)
				(hide yes)
			)
		)
		(property "Val" "12k"
			(at 314.96 101.6 90)
			(effects
				(font
					(size 1.27 1.27)
					(thickness 0.15)
				)
				(justify right)
			)
		)
		(property "Tolerance" "1%"
			(at 323.85 82.55 0)
			(effects
				(font
					(size 1.27 1.27)
				)
				(justify left bottom)
				(hide yes)
			)
		)
		(property "Public" ""
			(at 344.17 82.55 0)
			(effects
				(font
					(size 1.27 1.27)
				)
				(justify left bottom)
				(hide yes)
			)
		)
		(pin "1"
		)
		(pin "2"
		)
		(instances
			(project "polarfire-som"
				(path ""
					(reference "R166")
					(unit 1)
				)
			)
		)
	)
	(symbol
		(lib_id "antmicropower:+3V3")
		(at 325.12 143.51 0)
		(mirror y)
		(unit 1)
		(exclude_from_sim no)
		(in_bom yes)
		(on_board yes)
		(dnp no)
		(property "Reference" "#PWR0118"
			(at 325.12 147.32 0)
			(effects
				(font
					(size 1.27 1.27)
				)
				(hide yes)
			)
		)
		(property "Value" "+3V3"
			(at 325.12 139.7 0)
			(effects
				(font
					(size 1.27 1.27)
				)
			)
		)
		(property "Footprint" ""
			(at 325.12 143.51 0)
			(effects
				(font
					(size 1.27 1.27)
				)
				(hide yes)
			)
		)
		(property "Datasheet" ""
			(at 325.12 143.51 0)
			(effects
				(font
					(size 1.27 1.27)
				)
				(hide yes)
			)
		)
		(property "Description" ""
			(at 325.12 143.51 0)
			(effects
				(font
					(size 1.27 1.27)
				)
				(hide yes)
			)
		)
		(property "Author" "Antmicro"
			(at 309.88 146.05 0)
			(effects
				(font
					(size 1.27 1.27)
					(thickness 0.15)
				)
				(justify left bottom)
				(hide yes)
			)
		)
		(property "License" "Apache-2.0"
			(at 309.88 148.59 0)
			(effects
				(font
					(size 1.27 1.27)
					(thickness 0.15)
				)
				(justify left bottom)
				(hide yes)
			)
		)
		(pin "1"
		)
		(instances
			(project "polarfire-som"
				(path ""
					(reference "#PWR0118")
					(unit 1)
				)
			)
		)
	)
	(symbol
		(lib_id "antmicroInterfaceAnalogSwitchesSpecialPurpose:PI3USB102GZLEX")
		(at 254 146.05 0)
		(unit 1)
		(exclude_from_sim no)
		(in_bom yes)
		(on_board yes)
		(dnp no)
		(property "Reference" "U23"
			(at 256.54 140.97 0)
			(effects
				(font
					(size 1.27 1.27)
				)
				(justify left)
			)
		)
		(property "Value" "PI3USB102GZLEX"
			(at 256.54 143.5069 0)
			(effects
				(font
					(size 1.27 1.27)
				)
				(justify left)
			)
		)
		(property "Footprint" "antmicro-footprints:UQFN-10_1.4x1.8x0.5mm_P0.4mm"
			(at 254 166.37 0)
			(effects
				(font
					(size 1.27 1.27)
				)
				(hide yes)
			)
		)
		(property "Datasheet" "https://www.diodes.com/assets/Datasheets/PI3USB102G.pdf"
			(at 256.54 172.72 0)
			(effects
				(font
					(size 1.27 1.27)
				)
				(hide yes)
			)
		)
		(property "Description" "USB Switch IC 1 Channel 10-TQFN (1.3x1.6)"
			(at 254 146.05 0)
			(effects
				(font
					(size 1.27 1.27)
				)
				(hide yes)
			)
		)
		(property "MPN" "PI3USB102GZLEX"
			(at 289.56 161.29 0)
			(effects
				(font
					(size 1.27 1.27)
					(thickness 0.15)
				)
				(justify left bottom)
				(hide yes)
			)
		)
		(property "Manufacturer" "Diodes Incorporated"
			(at 289.56 163.83 0)
			(effects
				(font
					(size 1.27 1.27)
					(thickness 0.15)
				)
				(justify left bottom)
				(hide yes)
			)
		)
		(property "Author" "Antmicro"
			(at 289.56 166.37 0)
			(effects
				(font
					(size 1.27 1.27)
					(thickness 0.15)
				)
				(justify left bottom)
				(hide yes)
			)
		)
		(property "License" "Apache-2.0"
			(at 289.56 168.91 0)
			(effects
				(font
					(size 1.27 1.27)
					(thickness 0.15)
				)
				(justify left bottom)
				(hide yes)
			)
		)
		(pin "1"
		)
		(pin "10"
		)
		(pin "2"
		)
		(pin "3"
		)
		(pin "4"
		)
		(pin "5"
		)
		(pin "6"
		)
		(pin "7"
		)
		(pin "8"
		)
		(pin "9"
		)
		(instances
			(project "polarfire-som"
				(path ""
					(reference "U23")
					(unit 1)
				)
			)
		)
	)
	(symbol
		(lib_id "antmicroResistors0402:R_1k_0402")
		(at 160.02 55.88 90)
		(unit 1)
		(exclude_from_sim no)
		(in_bom yes)
		(on_board yes)
		(dnp yes)
		(property "Reference" "R58"
			(at 161.29 52.07 90)
			(effects
				(font
					(size 1.27 1.27)
					(thickness 0.15)
				)
				(justify right)
			)
		)
		(property "Value" "R_1k_0402"
			(at 172.72 35.56 0)
			(effects
				(font
					(size 1.27 1.27)
					(thickness 0.15)
				)
				(justify left bottom)
				(hide yes)
			)
		)
		(property "Footprint" "antmicro-footprints:R_0402_1005Metric"
			(at 175.26 35.56 0)
			(effects
				(font
					(size 1.27 1.27)
					(thickness 0.15)
				)
				(justify left bottom)
				(hide yes)
			)
		)
		(property "Datasheet" "https://www.bourns.com/docs/product-datasheets/cr.pdf"
			(at 177.8 35.56 0)
			(effects
				(font
					(size 1.27 1.27)
					(thickness 0.15)
				)
				(justify left bottom)
				(hide yes)
			)
		)
		(property "Description" "SMD Chip Resistor, 1 kohm, ± 1%, 63 mW, 0402 [1005 Metric], Thick Film, General Purpose"
			(at 160.02 55.88 0)
			(effects
				(font
					(size 1.27 1.27)
				)
				(hide yes)
			)
		)
		(property "MPN" "CR0402-FX-1001GLF"
			(at 180.34 35.56 0)
			(effects
				(font
					(size 1.27 1.27)
					(thickness 0.15)
				)
				(justify left bottom)
				(hide yes)
			)
		)
		(property "Manufacturer" "Bourns"
			(at 182.88 35.56 0)
			(effects
				(font
					(size 1.27 1.27)
					(thickness 0.15)
				)
				(justify left bottom)
				(hide yes)
			)
		)
		(property "License" "Apache-2.0"
			(at 185.42 35.56 0)
			(effects
				(font
					(size 1.27 1.27)
					(thickness 0.15)
				)
				(justify left bottom)
				(hide yes)
			)
		)
		(property "Author" "Antmicro"
			(at 187.96 35.56 0)
			(effects
				(font
					(size 1.27 1.27)
					(thickness 0.15)
				)
				(justify left bottom)
				(hide yes)
			)
		)
		(property "Val" "1k"
			(at 161.29 54.61 90)
			(effects
				(font
					(size 1.27 1.27)
					(thickness 0.15)
				)
				(justify right)
			)
		)
		(property "Tolerance" "1%"
			(at 170.18 35.56 0)
			(effects
				(font
					(size 1.27 1.27)
				)
				(justify left bottom)
				(hide yes)
			)
		)
		(property "DNP" "DNP"
			(at 160.02 55.88 90)
			(effects
				(font
					(size 1.27 1.27)
				)
				(hide yes)
			)
		)
		(property "Public" ""
			(at 190.5 35.56 0)
			(effects
				(font
					(size 1.27 1.27)
				)
				(justify left bottom)
				(hide yes)
			)
		)
		(pin "2"
		)
		(pin "1"
		)
		(instances
			(project "polarfire-som"
				(path ""
					(reference "R58")
					(unit 1)
				)
			)
		)
	)
	(symbol
		(lib_id "antmicroFerriteBeadsandChips:FB_470Z_1A_Murata-BLM18PG_0603")
		(at 77.47 133.35 0)
		(unit 1)
		(exclude_from_sim no)
		(in_bom yes)
		(on_board yes)
		(dnp no)
		(fields_autoplaced yes)
		(property "Reference" "FB1"
			(at 79.9719 127 0)
			(effects
				(font
					(size 1.27 1.27)
					(thickness 0.15)
				)
			)
		)
		(property "Value" "FB_470Z_1A_Murata-BLM18PG_0603"
			(at 91.44 135.89 0)
			(effects
				(font
					(size 1.27 1.27)
					(thickness 0.15)
				)
				(justify left bottom)
				(hide yes)
			)
		)
		(property "Footprint" "antmicro-footprints:FB_0603_1608Metric"
			(at 91.44 140.97 0)
			(effects
				(font
					(size 1.27 1.27)
					(thickness 0.15)
				)
				(justify left bottom)
				(hide yes)
			)
		)
		(property "Datasheet" "https://www.murata.com/en-us/products/productdata/8796738650142/ENFA0003.pdf"
			(at 91.44 143.51 0)
			(effects
				(font
					(size 1.27 1.27)
					(thickness 0.15)
				)
				(justify left bottom)
				(hide yes)
			)
		)
		(property "Description" "Ferrite Bead, 0603 [1608 Metric], 470 ohm, 1 A, BLM18P, 0.2 ohm, ± 25%, DC power line"
			(at 77.47 133.35 0)
			(effects
				(font
					(size 1.27 1.27)
				)
				(hide yes)
			)
		)
		(property "Val" "470Z/1A"
			(at 79.9719 129.54 0)
			(effects
				(font
					(size 1.27 1.27)
				)
			)
		)
		(property "MPN" "BLM18PG471SN1D"
			(at 91.44 146.05 0)
			(effects
				(font
					(size 1.27 1.27)
					(thickness 0.15)
				)
				(justify left bottom)
				(hide yes)
			)
		)
		(property "Manufacturer" "Murata"
			(at 91.44 148.59 0)
			(effects
				(font
					(size 1.27 1.27)
					(thickness 0.15)
				)
				(justify left bottom)
				(hide yes)
			)
		)
		(property "Current" ""
			(at 97.79 156.21 0)
			(effects
				(font
					(size 1.27 1.27)
					(thickness 0.15)
				)
				(justify left bottom)
				(hide yes)
			)
		)
		(property "Author" "Antmicro"
			(at 91.44 151.13 0)
			(effects
				(font
					(size 1.27 1.27)
					(thickness 0.15)
				)
				(justify left bottom)
				(hide yes)
			)
		)
		(property "License" "Apache-2.0"
			(at 91.44 153.67 0)
			(effects
				(font
					(size 1.27 1.27)
					(thickness 0.15)
				)
				(justify left bottom)
				(hide yes)
			)
		)
		(property "Public" ""
			(at 97.79 148.59 0)
			(effects
				(font
					(size 1.27 1.27)
				)
				(justify left bottom)
				(hide yes)
			)
		)
		(pin "1"
		)
		(pin "2"
		)
		(instances
			(project "polarfire-som"
				(path ""
					(reference "FB1")
					(unit 1)
				)
			)
		)
	)
	(symbol
		(lib_id "antmicroCapacitors0402:C_100n_0402")
		(at 245.11 135.89 90)
		(unit 1)
		(exclude_from_sim no)
		(in_bom yes)
		(on_board yes)
		(dnp no)
		(property "Reference" "C176"
			(at 247.65 132.0735 90)
			(effects
				(font
					(size 1.27 1.27)
					(thickness 0.15)
				)
				(justify right)
			)
		)
		(property "Value" "C_100n_0402"
			(at 255.27 115.57 0)
			(effects
				(font
					(size 1.27 1.27)
					(thickness 0.15)
				)
				(justify left bottom)
				(hide yes)
			)
		)
		(property "Footprint" "antmicro-footprints:C_0402_1005Metric"
			(at 257.81 115.57 0)
			(effects
				(font
					(size 1.27 1.27)
					(thickness 0.15)
				)
				(justify left bottom)
				(hide yes)
			)
		)
		(property "Datasheet" "https://www.murata.com/products/productdetail?partno=GRM155R61H104KE14%23"
			(at 260.35 115.57 0)
			(effects
				(font
					(size 1.27 1.27)
					(thickness 0.15)
				)
				(justify left bottom)
				(hide yes)
			)
		)
		(property "Description" "SMD Multilayer Ceramic Capacitor, 0.1 µF, 50 V, 0402 [1005 Metric], ± 10%, X5R, GRM Series"
			(at 245.11 135.89 0)
			(effects
				(font
					(size 1.27 1.27)
				)
				(hide yes)
			)
		)
		(property "MPN" "GRM155R61H104KE14D"
			(at 262.89 115.57 0)
			(effects
				(font
					(size 1.27 1.27)
					(thickness 0.15)
				)
				(justify left bottom)
				(hide yes)
			)
		)
		(property "Manufacturer" "Murata"
			(at 265.43 115.57 0)
			(effects
				(font
					(size 1.27 1.27)
					(thickness 0.15)
				)
				(justify left bottom)
				(hide yes)
			)
		)
		(property "License" "Apache-2.0"
			(at 267.97 115.57 0)
			(effects
				(font
					(size 1.27 1.27)
					(thickness 0.15)
				)
				(justify left bottom)
				(hide yes)
			)
		)
		(property "Author" "Antmicro"
			(at 270.51 115.57 0)
			(effects
				(font
					(size 1.27 1.27)
					(thickness 0.15)
				)
				(justify left bottom)
				(hide yes)
			)
		)
		(property "Val" "100n"
			(at 252.73 133.985 90)
			(effects
				(font
					(size 1.27 1.27)
					(thickness 0.15)
				)
				(justify left bottom)
			)
		)
		(property "Voltage" "50V"
			(at 273.05 115.57 0)
			(effects
				(font
					(size 1.27 1.27)
				)
				(justify left bottom)
				(hide yes)
			)
		)
		(property "Dielectric" "X5R"
			(at 275.59 115.57 0)
			(effects
				(font
					(size 1.27 1.27)
				)
				(justify left bottom)
				(hide yes)
			)
		)
		(property "Public" ""
			(at 278.13 115.57 0)
			(effects
				(font
					(size 1.27 1.27)
				)
				(justify left bottom)
				(hide yes)
			)
		)
		(pin "1"
		)
		(pin "2"
		)
		(instances
			(project "polarfire-som"
				(path ""
					(reference "C176")
					(unit 1)
				)
			)
		)
	)
	(symbol
		(lib_id "antmicropower:GND")
		(at 276.86 163.83 0)
		(unit 1)
		(exclude_from_sim no)
		(in_bom yes)
		(on_board yes)
		(dnp no)
		(fields_autoplaced yes)
		(property "Reference" "#PWR0206"
			(at 285.75 166.37 0)
			(effects
				(font
					(size 1.27 1.27)
					(thickness 0.15)
				)
				(justify left bottom)
				(hide yes)
			)
		)
		(property "Value" "GND"
			(at 276.86 168.91 0)
			(effects
				(font
					(size 1.27 1.27)
					(thickness 0.15)
				)
			)
		)
		(property "Footprint" ""
			(at 285.75 171.45 0)
			(effects
				(font
					(size 1.27 1.27)
					(thickness 0.15)
				)
				(justify left bottom)
				(hide yes)
			)
		)
		(property "Datasheet" ""
			(at 285.75 176.53 0)
			(effects
				(font
					(size 1.27 1.27)
					(thickness 0.15)
				)
				(justify left bottom)
				(hide yes)
			)
		)
		(property "Description" ""
			(at 276.86 163.83 0)
			(effects
				(font
					(size 1.27 1.27)
				)
				(hide yes)
			)
		)
		(property "Author" "Antmicro"
			(at 285.75 171.45 0)
			(effects
				(font
					(size 1.27 1.27)
					(thickness 0.15)
				)
				(justify left bottom)
				(hide yes)
			)
		)
		(property "License" "Apache-2.0"
			(at 285.75 173.99 0)
			(effects
				(font
					(size 1.27 1.27)
					(thickness 0.15)
				)
				(justify left bottom)
				(hide yes)
			)
		)
		(pin "1"
		)
		(instances
			(project "polarfire-som"
				(path ""
					(reference "#PWR0206")
					(unit 1)
				)
			)
		)
	)
	(symbol
		(lib_id "antmicropower:GND")
		(at 275.59 99.06 0)
		(unit 1)
		(exclude_from_sim no)
		(in_bom yes)
		(on_board yes)
		(dnp no)
		(fields_autoplaced yes)
		(property "Reference" "#PWR0199"
			(at 284.48 101.6 0)
			(effects
				(font
					(size 1.27 1.27)
					(thickness 0.15)
				)
				(justify left bottom)
				(hide yes)
			)
		)
		(property "Value" "GND"
			(at 275.59 104.14 0)
			(effects
				(font
					(size 1.27 1.27)
					(thickness 0.15)
				)
			)
		)
		(property "Footprint" ""
			(at 284.48 106.68 0)
			(effects
				(font
					(size 1.27 1.27)
					(thickness 0.15)
				)
				(justify left bottom)
				(hide yes)
			)
		)
		(property "Datasheet" ""
			(at 284.48 111.76 0)
			(effects
				(font
					(size 1.27 1.27)
					(thickness 0.15)
				)
				(justify left bottom)
				(hide yes)
			)
		)
		(property "Description" ""
			(at 275.59 99.06 0)
			(effects
				(font
					(size 1.27 1.27)
				)
				(hide yes)
			)
		)
		(property "Author" "Antmicro"
			(at 284.48 106.68 0)
			(effects
				(font
					(size 1.27 1.27)
					(thickness 0.15)
				)
				(justify left bottom)
				(hide yes)
			)
		)
		(property "License" "Apache-2.0"
			(at 284.48 109.22 0)
			(effects
				(font
					(size 1.27 1.27)
					(thickness 0.15)
				)
				(justify left bottom)
				(hide yes)
			)
		)
		(pin "1"
		)
		(instances
			(project "polarfire-som"
				(path ""
					(reference "#PWR0199")
					(unit 1)
				)
			)
		)
	)
	(symbol
		(lib_id "antmicroTestPoints:TP_0.75mm_SMD")
		(at 143.51 76.2 0)
		(unit 1)
		(exclude_from_sim no)
		(in_bom no)
		(on_board yes)
		(dnp no)
		(fields_autoplaced yes)
		(property "Reference" "TP11"
			(at 148.59 76.1999 0)
			(effects
				(font
					(size 1.27 1.27)
					(thickness 0.15)
				)
				(justify left)
			)
		)
		(property "Value" "TP_0.75mm_SMD"
			(at 154.305 80.01 0)
			(effects
				(font
					(size 1.27 1.27)
					(thickness 0.15)
				)
				(justify left bottom)
				(hide yes)
			)
		)
		(property "Footprint" "antmicro-footprints:TP_SMD_0.75mm"
			(at 154.305 82.55 0)
			(effects
				(font
					(size 1.27 1.27)
					(thickness 0.15)
				)
				(justify left bottom)
				(hide yes)
			)
		)
		(property "Datasheet" ""
			(at 161.29 88.9 0)
			(effects
				(font
					(size 1.27 1.27)
					(thickness 0.15)
				)
				(justify left bottom)
				(hide yes)
			)
		)
		(property "Description" "SMT test point"
			(at 143.51 76.2 0)
			(effects
				(font
					(size 1.27 1.27)
				)
				(hide yes)
			)
		)
		(property "MPN" ""
			(at 154.305 87.63 0)
			(effects
				(font
					(size 1.27 1.27)
					(thickness 0.15)
				)
				(justify left bottom)
				(hide yes)
			)
		)
		(property "Manufacturer" ""
			(at 154.305 82.55 0)
			(effects
				(font
					(size 1.27 1.27)
					(thickness 0.15)
				)
				(justify left bottom)
				(hide yes)
			)
		)
		(property "Author" "Antmicro"
			(at 154.305 85.09 0)
			(effects
				(font
					(size 1.27 1.27)
					(thickness 0.15)
				)
				(justify left bottom)
				(hide yes)
			)
		)
		(property "License" "Apache-2.0"
			(at 154.305 87.63 0)
			(effects
				(font
					(size 1.27 1.27)
					(thickness 0.15)
				)
				(justify left bottom)
				(hide yes)
			)
		)
		(property "Public" "False"
			(at 153.67 90.17 0)
			(effects
				(font
					(size 1.27 1.27)
				)
				(justify left bottom)
				(hide yes)
			)
		)
		(pin "1"
		)
		(instances
			(project "polarfire-som"
				(path ""
					(reference "TP11")
					(unit 1)
				)
			)
		)
	)
	(symbol
		(lib_id "antmicroCapacitors0402:C_1u_0402")
		(at 332.74 102.87 90)
		(unit 1)
		(exclude_from_sim no)
		(in_bom yes)
		(on_board yes)
		(dnp no)
		(fields_autoplaced yes)
		(property "Reference" "C292"
			(at 335.0641 99.493 90)
			(effects
				(font
					(size 1.27 1.27)
					(thickness 0.15)
				)
				(justify right)
			)
		)
		(property "Value" "C_1u_0402"
			(at 342.9 82.55 0)
			(effects
				(font
					(size 1.27 1.27)
					(thickness 0.15)
				)
				(justify left bottom)
				(hide yes)
			)
		)
		(property "Footprint" "antmicro-footprints:C_0402_1005Metric"
			(at 345.44 82.55 0)
			(effects
				(font
					(size 1.27 1.27)
					(thickness 0.15)
				)
				(justify left bottom)
				(hide yes)
			)
		)
		(property "Datasheet" "https://product.tdk.com/en/search/capacitor/ceramic/mlcc/info?part_no=C1005X6S1A105K050BC"
			(at 347.98 82.55 0)
			(effects
				(font
					(size 1.27 1.27)
					(thickness 0.15)
				)
				(justify left bottom)
				(hide yes)
			)
		)
		(property "Description" "SMD Multilayer Ceramic Capacitor, 1 µF, 10 V, 0402 [1005 Metric], ± 10%, X6S, C"
			(at 332.74 102.87 0)
			(effects
				(font
					(size 1.27 1.27)
				)
				(hide yes)
			)
		)
		(property "MPN" "C1005X6S1A105K050BC"
			(at 350.52 82.55 0)
			(effects
				(font
					(size 1.27 1.27)
					(thickness 0.15)
				)
				(justify left bottom)
				(hide yes)
			)
		)
		(property "Manufacturer" "TDK"
			(at 353.06 82.55 0)
			(effects
				(font
					(size 1.27 1.27)
					(thickness 0.15)
				)
				(justify left bottom)
				(hide yes)
			)
		)
		(property "License" "Apache-2.0"
			(at 355.6 82.55 0)
			(effects
				(font
					(size 1.27 1.27)
					(thickness 0.15)
				)
				(justify left bottom)
				(hide yes)
			)
		)
		(property "Author" "Antmicro"
			(at 358.14 82.55 0)
			(effects
				(font
					(size 1.27 1.27)
					(thickness 0.15)
				)
				(justify left bottom)
				(hide yes)
			)
		)
		(property "Val" "1u"
			(at 335.0641 102.0167 90)
			(effects
				(font
					(size 1.27 1.27)
					(thickness 0.15)
				)
				(justify right)
			)
		)
		(property "Voltage" ""
			(at 360.68 82.55 0)
			(effects
				(font
					(size 1.27 1.27)
				)
				(justify left bottom)
				(hide yes)
			)
		)
		(property "Dielectric" ""
			(at 363.22 82.55 0)
			(effects
				(font
					(size 1.27 1.27)
				)
				(justify left bottom)
				(hide yes)
			)
		)
		(property "Public" ""
			(at 365.76 82.55 0)
			(effects
				(font
					(size 1.27 1.27)
				)
				(justify left bottom)
				(hide yes)
			)
		)
		(pin "1"
		)
		(pin "2"
		)
		(instances
			(project "polarfire-som"
				(path ""
					(reference "C292")
					(unit 1)
				)
			)
		)
	)
	(symbol
		(lib_id "antmicropower:GND")
		(at 133.35 102.87 0)
		(mirror y)
		(unit 1)
		(exclude_from_sim no)
		(in_bom yes)
		(on_board yes)
		(dnp no)
		(fields_autoplaced yes)
		(property "Reference" "#PWR0170"
			(at 124.46 105.41 0)
			(effects
				(font
					(size 1.27 1.27)
					(thickness 0.15)
				)
				(justify left bottom)
				(hide yes)
			)
		)
		(property "Value" "GND"
			(at 133.35 107.95 0)
			(effects
				(font
					(size 1.27 1.27)
					(thickness 0.15)
				)
			)
		)
		(property "Footprint" ""
			(at 124.46 110.49 0)
			(effects
				(font
					(size 1.27 1.27)
					(thickness 0.15)
				)
				(justify left bottom)
				(hide yes)
			)
		)
		(property "Datasheet" ""
			(at 124.46 115.57 0)
			(effects
				(font
					(size 1.27 1.27)
					(thickness 0.15)
				)
				(justify left bottom)
				(hide yes)
			)
		)
		(property "Description" ""
			(at 133.35 102.87 0)
			(effects
				(font
					(size 1.27 1.27)
				)
				(hide yes)
			)
		)
		(property "Author" "Antmicro"
			(at 124.46 110.49 0)
			(effects
				(font
					(size 1.27 1.27)
					(thickness 0.15)
				)
				(justify left bottom)
				(hide yes)
			)
		)
		(property "License" "Apache-2.0"
			(at 124.46 113.03 0)
			(effects
				(font
					(size 1.27 1.27)
					(thickness 0.15)
				)
				(justify left bottom)
				(hide yes)
			)
		)
		(pin "1"
		)
		(instances
			(project "polarfire-som"
				(path ""
					(reference "#PWR0170")
					(unit 1)
				)
			)
		)
	)
	(symbol
		(lib_id "antmicropower:GND")
		(at 345.44 73.66 0)
		(unit 1)
		(exclude_from_sim no)
		(in_bom yes)
		(on_board yes)
		(dnp no)
		(fields_autoplaced yes)
		(property "Reference" "#PWR0123"
			(at 354.33 76.2 0)
			(effects
				(font
					(size 1.27 1.27)
					(thickness 0.15)
				)
				(justify left bottom)
				(hide yes)
			)
		)
		(property "Value" "GND"
			(at 345.44 78.74 0)
			(effects
				(font
					(size 1.27 1.27)
					(thickness 0.15)
				)
			)
		)
		(property "Footprint" ""
			(at 354.33 81.28 0)
			(effects
				(font
					(size 1.27 1.27)
					(thickness 0.15)
				)
				(justify left bottom)
				(hide yes)
			)
		)
		(property "Datasheet" ""
			(at 354.33 86.36 0)
			(effects
				(font
					(size 1.27 1.27)
					(thickness 0.15)
				)
				(justify left bottom)
				(hide yes)
			)
		)
		(property "Description" ""
			(at 345.44 73.66 0)
			(effects
				(font
					(size 1.27 1.27)
				)
				(hide yes)
			)
		)
		(property "Author" "Antmicro"
			(at 354.33 81.28 0)
			(effects
				(font
					(size 1.27 1.27)
					(thickness 0.15)
				)
				(justify left bottom)
				(hide yes)
			)
		)
		(property "License" "Apache-2.0"
			(at 354.33 83.82 0)
			(effects
				(font
					(size 1.27 1.27)
					(thickness 0.15)
				)
				(justify left bottom)
				(hide yes)
			)
		)
		(pin "1"
		)
		(instances
			(project "polarfire-som"
				(path ""
					(reference "#PWR0123")
					(unit 1)
				)
			)
		)
	)
	(symbol
		(lib_id "antmicropower:GND")
		(at 339.09 163.83 0)
		(unit 1)
		(exclude_from_sim no)
		(in_bom yes)
		(on_board yes)
		(dnp no)
		(fields_autoplaced yes)
		(property "Reference" "#PWR0120"
			(at 347.98 166.37 0)
			(effects
				(font
					(size 1.27 1.27)
					(thickness 0.15)
				)
				(justify left bottom)
				(hide yes)
			)
		)
		(property "Value" "GND"
			(at 339.09 168.91 0)
			(effects
				(font
					(size 1.27 1.27)
					(thickness 0.15)
				)
			)
		)
		(property "Footprint" ""
			(at 347.98 171.45 0)
			(effects
				(font
					(size 1.27 1.27)
					(thickness 0.15)
				)
				(justify left bottom)
				(hide yes)
			)
		)
		(property "Datasheet" ""
			(at 347.98 176.53 0)
			(effects
				(font
					(size 1.27 1.27)
					(thickness 0.15)
				)
				(justify left bottom)
				(hide yes)
			)
		)
		(property "Description" ""
			(at 339.09 163.83 0)
			(effects
				(font
					(size 1.27 1.27)
				)
				(hide yes)
			)
		)
		(property "Author" "Antmicro"
			(at 347.98 171.45 0)
			(effects
				(font
					(size 1.27 1.27)
					(thickness 0.15)
				)
				(justify left bottom)
				(hide yes)
			)
		)
		(property "License" "Apache-2.0"
			(at 347.98 173.99 0)
			(effects
				(font
					(size 1.27 1.27)
					(thickness 0.15)
				)
				(justify left bottom)
				(hide yes)
			)
		)
		(pin "1"
		)
		(instances
			(project "polarfire-som"
				(path ""
					(reference "#PWR0120")
					(unit 1)
				)
			)
		)
	)
	(symbol
		(lib_id "antmicropower:GND")
		(at 177.8 271.78 0)
		(unit 1)
		(exclude_from_sim no)
		(in_bom yes)
		(on_board yes)
		(dnp no)
		(property "Reference" "#PWR0145"
			(at 186.69 274.32 0)
			(effects
				(font
					(size 1.27 1.27)
					(thickness 0.15)
				)
				(justify left bottom)
				(hide yes)
			)
		)
		(property "Value" "GND"
			(at 177.8 275.59 0)
			(effects
				(font
					(size 1.27 1.27)
					(thickness 0.15)
				)
			)
		)
		(property "Footprint" ""
			(at 186.69 279.4 0)
			(effects
				(font
					(size 1.27 1.27)
					(thickness 0.15)
				)
				(justify left bottom)
				(hide yes)
			)
		)
		(property "Datasheet" ""
			(at 186.69 284.48 0)
			(effects
				(font
					(size 1.27 1.27)
					(thickness 0.15)
				)
				(justify left bottom)
				(hide yes)
			)
		)
		(property "Description" ""
			(at 177.8 271.78 0)
			(effects
				(font
					(size 1.27 1.27)
				)
				(hide yes)
			)
		)
		(property "Author" "Antmicro"
			(at 186.69 279.4 0)
			(effects
				(font
					(size 1.27 1.27)
					(thickness 0.15)
				)
				(justify left bottom)
				(hide yes)
			)
		)
		(property "License" "Apache-2.0"
			(at 186.69 281.94 0)
			(effects
				(font
					(size 1.27 1.27)
					(thickness 0.15)
				)
				(justify left bottom)
				(hide yes)
			)
		)
		(pin "1"
		)
		(instances
			(project "polarfire-som"
				(path ""
					(reference "#PWR0145")
					(unit 1)
				)
			)
		)
	)
	(symbol
		(lib_id "antmicroInterfaceControllers:USB2422-I_MJ")
		(at 276.86 62.23 0)
		(unit 1)
		(exclude_from_sim no)
		(in_bom yes)
		(on_board yes)
		(dnp no)
		(fields_autoplaced yes)
		(property "Reference" "U28"
			(at 293.37 54.61 0)
			(effects
				(font
					(size 1.27 1.27)
					(thickness 0.15)
				)
			)
		)
		(property "Value" "USB2422-I/MJ"
			(at 293.37 57.15 0)
			(effects
				(font
					(size 1.27 1.27)
					(thickness 0.15)
				)
			)
		)
		(property "Footprint" "antmicro-footprints:QFN-24-1EP_4x4mm_P0.5mm_EP2.6x2.6mm"
			(at 325.12 69.85 0)
			(effects
				(font
					(size 1.27 1.27)
					(thickness 0.15)
				)
				(justify left bottom)
				(hide yes)
			)
		)
		(property "Datasheet" "https://ww1.microchip.com/downloads/aemDocuments/documents/OTH/ProductDocuments/DataSheets/00001726B.pdf"
			(at 325.12 72.39 0)
			(effects
				(font
					(size 1.27 1.27)
					(thickness 0.15)
				)
				(justify left bottom)
				(hide yes)
			)
		)
		(property "Description" "USB Interface, USB Hub Controller, USB 2.0, 3 V, 3.6 V, SQFN, 24 Pins"
			(at 276.86 62.23 0)
			(effects
				(font
					(size 1.27 1.27)
				)
				(hide yes)
			)
		)
		(property "Author" "Antmicro"
			(at 325.12 74.93 0)
			(effects
				(font
					(size 1.27 1.27)
					(thickness 0.15)
				)
				(justify left bottom)
				(hide yes)
			)
		)
		(property "License" "Apache-2.0"
			(at 325.12 77.47 0)
			(effects
				(font
					(size 1.27 1.27)
					(thickness 0.15)
				)
				(justify left bottom)
				(hide yes)
			)
		)
		(property "MPN" "USB2422-I/MJ"
			(at 325.12 80.01 0)
			(effects
				(font
					(size 1.27 1.27)
					(thickness 0.15)
				)
				(justify left bottom)
				(hide yes)
			)
		)
		(property "Manufacturer" "Microchip Technology"
			(at 325.12 82.55 0)
			(effects
				(font
					(size 1.27 1.27)
					(thickness 0.15)
				)
				(justify left bottom)
				(hide yes)
			)
		)
		(pin "1"
		)
		(pin "10"
		)
		(pin "11"
		)
		(pin "12"
		)
		(pin "13"
		)
		(pin "14"
		)
		(pin "15"
		)
		(pin "16"
		)
		(pin "17"
		)
		(pin "18"
		)
		(pin "19"
		)
		(pin "2"
		)
		(pin "20"
		)
		(pin "21"
		)
		(pin "22"
		)
		(pin "23"
		)
		(pin "24"
		)
		(pin "25"
		)
		(pin "3"
		)
		(pin "4"
		)
		(pin "5"
		)
		(pin "6"
		)
		(pin "7"
		)
		(pin "8"
		)
		(pin "9"
		)
		(instances
			(project "polarfire-som"
				(path ""
					(reference "U28")
					(unit 1)
				)
			)
		)
	)
	(symbol
		(lib_id "antmicroCapacitors0402:C_100n_0402")
		(at 107.95 140.97 90)
		(unit 1)
		(exclude_from_sim no)
		(in_bom yes)
		(on_board yes)
		(dnp no)
		(property "Reference" "C183"
			(at 110.49 137.1535 90)
			(effects
				(font
					(size 1.27 1.27)
					(thickness 0.15)
				)
				(justify right)
			)
		)
		(property "Value" "C_100n_0402"
			(at 118.11 120.65 0)
			(effects
				(font
					(size 1.27 1.27)
					(thickness 0.15)
				)
				(justify left bottom)
				(hide yes)
			)
		)
		(property "Footprint" "antmicro-footprints:C_0402_1005Metric"
			(at 120.65 120.65 0)
			(effects
				(font
					(size 1.27 1.27)
					(thickness 0.15)
				)
				(justify left bottom)
				(hide yes)
			)
		)
		(property "Datasheet" "https://www.murata.com/products/productdetail?partno=GRM155R61H104KE14%23"
			(at 123.19 120.65 0)
			(effects
				(font
					(size 1.27 1.27)
					(thickness 0.15)
				)
				(justify left bottom)
				(hide yes)
			)
		)
		(property "Description" "SMD Multilayer Ceramic Capacitor, 0.1 µF, 50 V, 0402 [1005 Metric], ± 10%, X5R, GRM Series"
			(at 107.95 140.97 0)
			(effects
				(font
					(size 1.27 1.27)
				)
				(hide yes)
			)
		)
		(property "MPN" "GRM155R61H104KE14D"
			(at 125.73 120.65 0)
			(effects
				(font
					(size 1.27 1.27)
					(thickness 0.15)
				)
				(justify left bottom)
				(hide yes)
			)
		)
		(property "Manufacturer" "Murata"
			(at 128.27 120.65 0)
			(effects
				(font
					(size 1.27 1.27)
					(thickness 0.15)
				)
				(justify left bottom)
				(hide yes)
			)
		)
		(property "License" "Apache-2.0"
			(at 130.81 120.65 0)
			(effects
				(font
					(size 1.27 1.27)
					(thickness 0.15)
				)
				(justify left bottom)
				(hide yes)
			)
		)
		(property "Author" "Antmicro"
			(at 133.35 120.65 0)
			(effects
				(font
					(size 1.27 1.27)
					(thickness 0.15)
				)
				(justify left bottom)
				(hide yes)
			)
		)
		(property "Val" "100n"
			(at 115.57 139.065 90)
			(effects
				(font
					(size 1.27 1.27)
					(thickness 0.15)
				)
				(justify left bottom)
			)
		)
		(property "Voltage" "50V"
			(at 135.89 120.65 0)
			(effects
				(font
					(size 1.27 1.27)
				)
				(justify left bottom)
				(hide yes)
			)
		)
		(property "Dielectric" "X5R"
			(at 138.43 120.65 0)
			(effects
				(font
					(size 1.27 1.27)
				)
				(justify left bottom)
				(hide yes)
			)
		)
		(property "Public" ""
			(at 140.97 120.65 0)
			(effects
				(font
					(size 1.27 1.27)
				)
				(justify left bottom)
				(hide yes)
			)
		)
		(pin "1"
		)
		(pin "2"
		)
		(instances
			(project "polarfire-som"
				(path ""
					(reference "C183")
					(unit 1)
				)
			)
		)
	)
	(symbol
		(lib_id "antmicroCapacitors0402:C_100n_0402")
		(at 73.66 140.97 90)
		(unit 1)
		(exclude_from_sim no)
		(in_bom yes)
		(on_board yes)
		(dnp no)
		(property "Reference" "C186"
			(at 73.66 135.89 90)
			(effects
				(font
					(size 1.27 1.27)
					(thickness 0.15)
				)
				(justify right)
			)
		)
		(property "Value" "C_100n_0402"
			(at 83.82 120.65 0)
			(effects
				(font
					(size 1.27 1.27)
					(thickness 0.15)
				)
				(justify left bottom)
				(hide yes)
			)
		)
		(property "Footprint" "antmicro-footprints:C_0402_1005Metric"
			(at 86.36 120.65 0)
			(effects
				(font
					(size 1.27 1.27)
					(thickness 0.15)
				)
				(justify left bottom)
				(hide yes)
			)
		)
		(property "Datasheet" "https://www.murata.com/products/productdetail?partno=GRM155R61H104KE14%23"
			(at 88.9 120.65 0)
			(effects
				(font
					(size 1.27 1.27)
					(thickness 0.15)
				)
				(justify left bottom)
				(hide yes)
			)
		)
		(property "Description" "SMD Multilayer Ceramic Capacitor, 0.1 µF, 50 V, 0402 [1005 Metric], ± 10%, X5R, GRM Series"
			(at 73.66 140.97 0)
			(effects
				(font
					(size 1.27 1.27)
				)
				(hide yes)
			)
		)
		(property "MPN" "GRM155R61H104KE14D"
			(at 91.44 120.65 0)
			(effects
				(font
					(size 1.27 1.27)
					(thickness 0.15)
				)
				(justify left bottom)
				(hide yes)
			)
		)
		(property "Manufacturer" "Murata"
			(at 93.98 120.65 0)
			(effects
				(font
					(size 1.27 1.27)
					(thickness 0.15)
				)
				(justify left bottom)
				(hide yes)
			)
		)
		(property "License" "Apache-2.0"
			(at 96.52 120.65 0)
			(effects
				(font
					(size 1.27 1.27)
					(thickness 0.15)
				)
				(justify left bottom)
				(hide yes)
			)
		)
		(property "Author" "Antmicro"
			(at 99.06 120.65 0)
			(effects
				(font
					(size 1.27 1.27)
					(thickness 0.15)
				)
				(justify left bottom)
				(hide yes)
			)
		)
		(property "Val" "100n"
			(at 78.74 139.7 90)
			(effects
				(font
					(size 1.27 1.27)
					(thickness 0.15)
				)
				(justify left bottom)
			)
		)
		(property "Voltage" "50V"
			(at 101.6 120.65 0)
			(effects
				(font
					(size 1.27 1.27)
				)
				(justify left bottom)
				(hide yes)
			)
		)
		(property "Dielectric" "X5R"
			(at 104.14 120.65 0)
			(effects
				(font
					(size 1.27 1.27)
				)
				(justify left bottom)
				(hide yes)
			)
		)
		(property "Public" ""
			(at 106.68 120.65 0)
			(effects
				(font
					(size 1.27 1.27)
				)
				(justify left bottom)
				(hide yes)
			)
		)
		(pin "1"
		)
		(pin "2"
		)
		(instances
			(project "polarfire-som"
				(path ""
					(reference "C186")
					(unit 1)
				)
			)
		)
	)
	(symbol
		(lib_id "antmicropower:GND")
		(at 245.11 137.16 0)
		(unit 1)
		(exclude_from_sim no)
		(in_bom yes)
		(on_board yes)
		(dnp no)
		(fields_autoplaced yes)
		(property "Reference" "#PWR0122"
			(at 254 139.7 0)
			(effects
				(font
					(size 1.27 1.27)
					(thickness 0.15)
				)
				(justify left bottom)
				(hide yes)
			)
		)
		(property "Value" "GND"
			(at 245.11 142.24 0)
			(effects
				(font
					(size 1.27 1.27)
					(thickness 0.15)
				)
			)
		)
		(property "Footprint" ""
			(at 254 144.78 0)
			(effects
				(font
					(size 1.27 1.27)
					(thickness 0.15)
				)
				(justify left bottom)
				(hide yes)
			)
		)
		(property "Datasheet" ""
			(at 254 149.86 0)
			(effects
				(font
					(size 1.27 1.27)
					(thickness 0.15)
				)
				(justify left bottom)
				(hide yes)
			)
		)
		(property "Description" ""
			(at 245.11 137.16 0)
			(effects
				(font
					(size 1.27 1.27)
				)
				(hide yes)
			)
		)
		(property "Author" "Antmicro"
			(at 254 144.78 0)
			(effects
				(font
					(size 1.27 1.27)
					(thickness 0.15)
				)
				(justify left bottom)
				(hide yes)
			)
		)
		(property "License" "Apache-2.0"
			(at 254 147.32 0)
			(effects
				(font
					(size 1.27 1.27)
					(thickness 0.15)
				)
				(justify left bottom)
				(hide yes)
			)
		)
		(pin "1"
		)
		(instances
			(project "polarfire-som"
				(path ""
					(reference "#PWR0122")
					(unit 1)
				)
			)
		)
	)
	(symbol
		(lib_id "antmicroResistors0402:R_100k_0402")
		(at 271.78 93.98 180)
		(unit 1)
		(exclude_from_sim no)
		(in_bom yes)
		(on_board yes)
		(dnp no)
		(property "Reference" "R100"
			(at 269.24 91.44 0)
			(effects
				(font
					(size 1.27 1.27)
					(thickness 0.15)
				)
			)
		)
		(property "Value" "R_100k_0402"
			(at 251.46 81.28 0)
			(effects
				(font
					(size 1.27 1.27)
					(thickness 0.15)
				)
				(justify left bottom)
				(hide yes)
			)
		)
		(property "Footprint" "antmicro-footprints:R_0402_1005Metric"
			(at 251.46 78.74 0)
			(effects
				(font
					(size 1.27 1.27)
					(thickness 0.15)
				)
				(justify left bottom)
				(hide yes)
			)
		)
		(property "Datasheet" "https://www.bourns.com/docs/product-datasheets/cr.pdf"
			(at 251.46 76.2 0)
			(effects
				(font
					(size 1.27 1.27)
					(thickness 0.15)
				)
				(justify left bottom)
				(hide yes)
			)
		)
		(property "Description" "SMD Chip Resistor, 100 kohm, ± 1%, 62.5 mW, 0402 [1005 Metric], Thick Film, General Purpose"
			(at 271.78 93.98 0)
			(effects
				(font
					(size 1.27 1.27)
				)
				(hide yes)
			)
		)
		(property "MPN" "CR0402-FX-1003GLF"
			(at 251.46 73.66 0)
			(effects
				(font
					(size 1.27 1.27)
					(thickness 0.15)
				)
				(justify left bottom)
				(hide yes)
			)
		)
		(property "Manufacturer" "Bourns"
			(at 251.46 71.12 0)
			(effects
				(font
					(size 1.27 1.27)
					(thickness 0.15)
				)
				(justify left bottom)
				(hide yes)
			)
		)
		(property "License" "Apache-2.0"
			(at 251.46 68.58 0)
			(effects
				(font
					(size 1.27 1.27)
					(thickness 0.15)
				)
				(justify left bottom)
				(hide yes)
			)
		)
		(property "Author" "Antmicro"
			(at 251.46 66.04 0)
			(effects
				(font
					(size 1.27 1.27)
					(thickness 0.15)
				)
				(justify left bottom)
				(hide yes)
			)
		)
		(property "Val" "100k"
			(at 269.24 96.52 0)
			(effects
				(font
					(size 1.27 1.27)
					(thickness 0.15)
				)
			)
		)
		(property "Tolerance" "1%"
			(at 251.46 83.82 0)
			(effects
				(font
					(size 1.27 1.27)
				)
				(justify left bottom)
				(hide yes)
			)
		)
		(property "Public" ""
			(at 251.46 63.5 0)
			(effects
				(font
					(size 1.27 1.27)
				)
				(justify left bottom)
				(hide yes)
			)
		)
		(pin "1"
		)
		(pin "2"
		)
		(instances
			(project "polarfire-som"
				(path ""
					(reference "R100")
					(unit 1)
				)
			)
		)
	)
	(symbol
		(lib_id "antmicroOscillators:Oscillator_24MHz_ESC_2016MV")
		(at 187.96 264.16 0)
		(unit 1)
		(exclude_from_sim no)
		(in_bom yes)
		(on_board yes)
		(dnp no)
		(fields_autoplaced yes)
		(property "Reference" "Y1"
			(at 197.485 254 0)
			(effects
				(font
					(size 1.27 1.27)
					(thickness 0.15)
				)
			)
		)
		(property "Value" "Oscillator_24MHz_ESC_2016MV"
			(at 205.74 279.4 0)
			(effects
				(font
					(size 1.27 1.27)
					(thickness 0.15)
				)
				(justify left bottom)
				(hide yes)
			)
		)
		(property "Footprint" "antmicro-footprints:Oscillator_SMD_ECS_2016MV_2x1.6x0.85mm"
			(at 205.74 281.94 0)
			(effects
				(font
					(size 1.27 1.27)
					(thickness 0.15)
				)
				(justify left bottom)
				(hide yes)
			)
		)
		(property "Datasheet" "https://ecsxtal.com/store/pdf/ECS-2016MV.pdf"
			(at 205.74 284.48 0)
			(effects
				(font
					(size 1.27 1.27)
					(thickness 0.15)
				)
				(justify left bottom)
				(hide yes)
			)
		)
		(property "Description" "Oscillator, 24 MHz XO (Standard) CMOS 1.6V ~ 3.6V Enable/Disable 4-SMD, No Lead"
			(at 187.96 264.16 0)
			(effects
				(font
					(size 1.27 1.27)
				)
				(hide yes)
			)
		)
		(property "MPN" "ECS-2016MV-240-CN-TR"
			(at 197.485 256.54 0)
			(effects
				(font
					(size 1.27 1.27)
					(thickness 0.15)
				)
			)
		)
		(property "Manufacturer" "ECS Inc. International"
			(at 205.74 274.32 0)
			(effects
				(font
					(size 1.27 1.27)
					(thickness 0.15)
				)
				(justify left bottom)
				(hide yes)
			)
		)
		(property "Val" "24 MHz"
			(at 197.485 259.08 0)
			(effects
				(font
					(size 1.27 1.27)
					(thickness 0.15)
				)
			)
		)
		(property "Author" "Antmicro"
			(at 205.74 287.02 0)
			(effects
				(font
					(size 1.27 1.27)
					(thickness 0.15)
				)
				(justify left bottom)
				(hide yes)
			)
		)
		(property "License" "Apache-2.0"
			(at 205.74 289.56 0)
			(effects
				(font
					(size 1.27 1.27)
					(thickness 0.15)
				)
				(justify left bottom)
				(hide yes)
			)
		)
		(property "Public" ""
			(at 219.71 288.29 0)
			(effects
				(font
					(size 1.27 1.27)
				)
				(justify left bottom)
				(hide yes)
			)
		)
		(pin "4"
		)
		(pin "3"
		)
		(pin "2"
		)
		(pin "1"
		)
		(instances
			(project "polarfire-som"
				(path ""
					(reference "Y1")
					(unit 1)
				)
			)
		)
	)
	(symbol
		(lib_id "antmicroCapacitors0402:C_100n_0402")
		(at 363.22 71.12 90)
		(unit 1)
		(exclude_from_sim no)
		(in_bom yes)
		(on_board yes)
		(dnp no)
		(property "Reference" "C223"
			(at 364.49 67.31 90)
			(effects
				(font
					(size 1.27 1.27)
					(thickness 0.15)
				)
				(justify right)
			)
		)
		(property "Value" "C_100n_0402"
			(at 373.38 50.8 0)
			(effects
				(font
					(size 1.27 1.27)
					(thickness 0.15)
				)
				(justify left bottom)
				(hide yes)
			)
		)
		(property "Footprint" "antmicro-footprints:C_0402_1005Metric"
			(at 375.92 50.8 0)
			(effects
				(font
					(size 1.27 1.27)
					(thickness 0.15)
				)
				(justify left bottom)
				(hide yes)
			)
		)
		(property "Datasheet" "https://www.murata.com/products/productdetail?partno=GRM155R61H104KE14%23"
			(at 378.46 50.8 0)
			(effects
				(font
					(size 1.27 1.27)
					(thickness 0.15)
				)
				(justify left bottom)
				(hide yes)
			)
		)
		(property "Description" "SMD Multilayer Ceramic Capacitor, 0.1 µF, 50 V, 0402 [1005 Metric], ± 10%, X5R, GRM Series"
			(at 363.22 71.12 0)
			(effects
				(font
					(size 1.27 1.27)
				)
				(hide yes)
			)
		)
		(property "MPN" "GRM155R61H104KE14D"
			(at 381 50.8 0)
			(effects
				(font
					(size 1.27 1.27)
					(thickness 0.15)
				)
				(justify left bottom)
				(hide yes)
			)
		)
		(property "Manufacturer" "Murata"
			(at 383.54 50.8 0)
			(effects
				(font
					(size 1.27 1.27)
					(thickness 0.15)
				)
				(justify left bottom)
				(hide yes)
			)
		)
		(property "License" "Apache-2.0"
			(at 386.08 50.8 0)
			(effects
				(font
					(size 1.27 1.27)
					(thickness 0.15)
				)
				(justify left bottom)
				(hide yes)
			)
		)
		(property "Author" "Antmicro"
			(at 388.62 50.8 0)
			(effects
				(font
					(size 1.27 1.27)
					(thickness 0.15)
				)
				(justify left bottom)
				(hide yes)
			)
		)
		(property "Val" "100n"
			(at 369.57 69.85 90)
			(effects
				(font
					(size 1.27 1.27)
					(thickness 0.15)
				)
				(justify left bottom)
			)
		)
		(property "Voltage" "50V"
			(at 391.16 50.8 0)
			(effects
				(font
					(size 1.27 1.27)
				)
				(justify left bottom)
				(hide yes)
			)
		)
		(property "Dielectric" "X5R"
			(at 393.7 50.8 0)
			(effects
				(font
					(size 1.27 1.27)
				)
				(justify left bottom)
				(hide yes)
			)
		)
		(property "Public" ""
			(at 396.24 50.8 0)
			(effects
				(font
					(size 1.27 1.27)
				)
				(justify left bottom)
				(hide yes)
			)
		)
		(pin "1"
		)
		(pin "2"
		)
		(instances
			(project "polarfire-som"
				(path ""
					(reference "C223")
					(unit 1)
				)
			)
		)
	)
	(symbol
		(lib_id "antmicroCapacitors0402:C_100n_0402")
		(at 177.8 269.24 90)
		(unit 1)
		(exclude_from_sim no)
		(in_bom yes)
		(on_board yes)
		(dnp no)
		(property "Reference" "C177"
			(at 179.07 265.43 90)
			(effects
				(font
					(size 1.27 1.27)
					(thickness 0.15)
				)
				(justify right)
			)
		)
		(property "Value" "C_100n_0402"
			(at 187.96 248.92 0)
			(effects
				(font
					(size 1.27 1.27)
					(thickness 0.15)
				)
				(justify left bottom)
				(hide yes)
			)
		)
		(property "Footprint" "antmicro-footprints:C_0402_1005Metric"
			(at 190.5 248.92 0)
			(effects
				(font
					(size 1.27 1.27)
					(thickness 0.15)
				)
				(justify left bottom)
				(hide yes)
			)
		)
		(property "Datasheet" "https://www.murata.com/products/productdetail?partno=GRM155R61H104KE14%23"
			(at 193.04 248.92 0)
			(effects
				(font
					(size 1.27 1.27)
					(thickness 0.15)
				)
				(justify left bottom)
				(hide yes)
			)
		)
		(property "Description" "SMD Multilayer Ceramic Capacitor, 0.1 µF, 50 V, 0402 [1005 Metric], ± 10%, X5R, GRM Series"
			(at 177.8 269.24 0)
			(effects
				(font
					(size 1.27 1.27)
				)
				(hide yes)
			)
		)
		(property "MPN" "GRM155R61H104KE14D"
			(at 195.58 248.92 0)
			(effects
				(font
					(size 1.27 1.27)
					(thickness 0.15)
				)
				(justify left bottom)
				(hide yes)
			)
		)
		(property "Manufacturer" "Murata"
			(at 198.12 248.92 0)
			(effects
				(font
					(size 1.27 1.27)
					(thickness 0.15)
				)
				(justify left bottom)
				(hide yes)
			)
		)
		(property "License" "Apache-2.0"
			(at 200.66 248.92 0)
			(effects
				(font
					(size 1.27 1.27)
					(thickness 0.15)
				)
				(justify left bottom)
				(hide yes)
			)
		)
		(property "Author" "Antmicro"
			(at 203.2 248.92 0)
			(effects
				(font
					(size 1.27 1.27)
					(thickness 0.15)
				)
				(justify left bottom)
				(hide yes)
			)
		)
		(property "Val" "100n"
			(at 184.15 267.97 90)
			(effects
				(font
					(size 1.27 1.27)
					(thickness 0.15)
				)
				(justify left bottom)
			)
		)
		(property "Voltage" "50V"
			(at 205.74 248.92 0)
			(effects
				(font
					(size 1.27 1.27)
				)
				(justify left bottom)
				(hide yes)
			)
		)
		(property "Dielectric" "X5R"
			(at 208.28 248.92 0)
			(effects
				(font
					(size 1.27 1.27)
				)
				(justify left bottom)
				(hide yes)
			)
		)
		(property "Public" ""
			(at 210.82 248.92 0)
			(effects
				(font
					(size 1.27 1.27)
				)
				(justify left bottom)
				(hide yes)
			)
		)
		(pin "1"
		)
		(pin "2"
		)
		(instances
			(project "polarfire-som"
				(path ""
					(reference "C177")
					(unit 1)
				)
			)
		)
	)
	(symbol
		(lib_id "antmicropower:GND")
		(at 147.32 99.06 0)
		(unit 1)
		(exclude_from_sim no)
		(in_bom yes)
		(on_board yes)
		(dnp no)
		(fields_autoplaced yes)
		(property "Reference" "#PWR0168"
			(at 156.21 101.6 0)
			(effects
				(font
					(size 1.27 1.27)
					(thickness 0.15)
				)
				(justify left bottom)
				(hide yes)
			)
		)
		(property "Value" "GND"
			(at 147.32 104.14 0)
			(effects
				(font
					(size 1.27 1.27)
					(thickness 0.15)
				)
			)
		)
		(property "Footprint" ""
			(at 156.21 106.68 0)
			(effects
				(font
					(size 1.27 1.27)
					(thickness 0.15)
				)
				(justify left bottom)
				(hide yes)
			)
		)
		(property "Datasheet" ""
			(at 156.21 111.76 0)
			(effects
				(font
					(size 1.27 1.27)
					(thickness 0.15)
				)
				(justify left bottom)
				(hide yes)
			)
		)
		(property "Description" ""
			(at 147.32 99.06 0)
			(effects
				(font
					(size 1.27 1.27)
				)
				(hide yes)
			)
		)
		(property "Author" "Antmicro"
			(at 156.21 106.68 0)
			(effects
				(font
					(size 1.27 1.27)
					(thickness 0.15)
				)
				(justify left bottom)
				(hide yes)
			)
		)
		(property "License" "Apache-2.0"
			(at 156.21 109.22 0)
			(effects
				(font
					(size 1.27 1.27)
					(thickness 0.15)
				)
				(justify left bottom)
				(hide yes)
			)
		)
		(pin "1"
		)
		(instances
			(project "polarfire-som"
				(path ""
					(reference "#PWR0168")
					(unit 1)
				)
			)
		)
	)
	(symbol
		(lib_id "antmicropower:+3V3")
		(at 177.8 261.62 0)
		(unit 1)
		(exclude_from_sim no)
		(in_bom yes)
		(on_board yes)
		(dnp no)
		(fields_autoplaced yes)
		(property "Reference" "#PWR0144"
			(at 193.04 264.16 0)
			(effects
				(font
					(size 1.27 1.27)
					(thickness 0.15)
				)
				(justify left bottom)
				(hide yes)
			)
		)
		(property "Value" "+3V3"
			(at 177.8 256.54 0)
			(effects
				(font
					(size 1.27 1.27)
					(thickness 0.15)
				)
			)
		)
		(property "Footprint" ""
			(at 193.04 269.24 0)
			(effects
				(font
					(size 1.27 1.27)
					(thickness 0.15)
				)
				(justify left bottom)
				(hide yes)
			)
		)
		(property "Datasheet" ""
			(at 193.04 271.78 0)
			(effects
				(font
					(size 1.27 1.27)
					(thickness 0.15)
				)
				(justify left bottom)
				(hide yes)
			)
		)
		(property "Description" ""
			(at 177.8 261.62 0)
			(effects
				(font
					(size 1.27 1.27)
				)
				(hide yes)
			)
		)
		(property "Author" "Antmicro"
			(at 193.04 269.24 0)
			(effects
				(font
					(size 1.27 1.27)
					(thickness 0.15)
				)
				(justify left bottom)
				(hide yes)
			)
		)
		(property "License" "Apache-2.0"
			(at 193.04 271.78 0)
			(effects
				(font
					(size 1.27 1.27)
					(thickness 0.15)
				)
				(justify left bottom)
				(hide yes)
			)
		)
		(pin "1"
		)
		(instances
			(project "polarfire-som"
				(path ""
					(reference "#PWR0144")
					(unit 1)
				)
			)
		)
	)
	(symbol
		(lib_id "antmicroResistors0402:R_10k_0402")
		(at 74.93 185.42 90)
		(unit 1)
		(exclude_from_sim no)
		(in_bom yes)
		(on_board yes)
		(dnp no)
		(property "Reference" "R77"
			(at 77.47 181.61 90)
			(effects
				(font
					(size 1.27 1.27)
					(thickness 0.15)
				)
				(justify right)
			)
		)
		(property "Value" "R_10k_0402"
			(at 87.63 165.1 0)
			(effects
				(font
					(size 1.27 1.27)
					(thickness 0.15)
				)
				(justify left bottom)
				(hide yes)
			)
		)
		(property "Footprint" "antmicro-footprints:R_0402_1005Metric"
			(at 90.17 165.1 0)
			(effects
				(font
					(size 1.27 1.27)
					(thickness 0.15)
				)
				(justify left bottom)
				(hide yes)
			)
		)
		(property "Datasheet" "https://www.bourns.com/docs/product-datasheets/cr.pdf"
			(at 92.71 165.1 0)
			(effects
				(font
					(size 1.27 1.27)
					(thickness 0.15)
				)
				(justify left bottom)
				(hide yes)
			)
		)
		(property "Description" "SMD Chip Resistor, 10 kohm, ± 1%, 62.5 mW, 0402 [1005 Metric], Thick Film, General Purpose"
			(at 74.93 185.42 0)
			(effects
				(font
					(size 1.27 1.27)
				)
				(hide yes)
			)
		)
		(property "MPN" "CR0402-FX-1002GLF"
			(at 95.25 165.1 0)
			(effects
				(font
					(size 1.27 1.27)
					(thickness 0.15)
				)
				(justify left bottom)
				(hide yes)
			)
		)
		(property "Manufacturer" "Bourns"
			(at 97.79 165.1 0)
			(effects
				(font
					(size 1.27 1.27)
					(thickness 0.15)
				)
				(justify left bottom)
				(hide yes)
			)
		)
		(property "License" "Apache-2.0"
			(at 100.33 165.1 0)
			(effects
				(font
					(size 1.27 1.27)
					(thickness 0.15)
				)
				(justify left bottom)
				(hide yes)
			)
		)
		(property "Author" "Antmicro"
			(at 102.87 165.1 0)
			(effects
				(font
					(size 1.27 1.27)
					(thickness 0.15)
				)
				(justify left bottom)
				(hide yes)
			)
		)
		(property "Val" "10k"
			(at 77.47 184.15 90)
			(effects
				(font
					(size 1.27 1.27)
					(thickness 0.15)
				)
				(justify right)
			)
		)
		(property "Tolerance" "1%"
			(at 85.09 165.1 0)
			(effects
				(font
					(size 1.27 1.27)
				)
				(justify left bottom)
				(hide yes)
			)
		)
		(property "Public" ""
			(at 105.41 165.1 0)
			(effects
				(font
					(size 1.27 1.27)
				)
				(justify left bottom)
				(hide yes)
			)
		)
		(pin "1"
		)
		(pin "2"
		)
		(instances
			(project "polarfire-som"
				(path ""
					(reference "R77")
					(unit 1)
				)
			)
		)
	)
	(symbol
		(lib_id "antmicropower:GND")
		(at 107.95 142.24 0)
		(unit 1)
		(exclude_from_sim no)
		(in_bom yes)
		(on_board yes)
		(dnp no)
		(property "Reference" "#PWR0155"
			(at 116.84 144.78 0)
			(effects
				(font
					(size 1.27 1.27)
					(thickness 0.15)
				)
				(justify left bottom)
				(hide yes)
			)
		)
		(property "Value" "GND"
			(at 107.95 146.05 0)
			(effects
				(font
					(size 1.27 1.27)
					(thickness 0.15)
				)
			)
		)
		(property "Footprint" ""
			(at 116.84 149.86 0)
			(effects
				(font
					(size 1.27 1.27)
					(thickness 0.15)
				)
				(justify left bottom)
				(hide yes)
			)
		)
		(property "Datasheet" ""
			(at 116.84 154.94 0)
			(effects
				(font
					(size 1.27 1.27)
					(thickness 0.15)
				)
				(justify left bottom)
				(hide yes)
			)
		)
		(property "Description" ""
			(at 107.95 142.24 0)
			(effects
				(font
					(size 1.27 1.27)
				)
				(hide yes)
			)
		)
		(property "Author" "Antmicro"
			(at 116.84 149.86 0)
			(effects
				(font
					(size 1.27 1.27)
					(thickness 0.15)
				)
				(justify left bottom)
				(hide yes)
			)
		)
		(property "License" "Apache-2.0"
			(at 116.84 152.4 0)
			(effects
				(font
					(size 1.27 1.27)
					(thickness 0.15)
				)
				(justify left bottom)
				(hide yes)
			)
		)
		(pin "1"
		)
		(instances
			(project "polarfire-som"
				(path ""
					(reference "#PWR0155")
					(unit 1)
				)
			)
		)
	)
	(symbol
		(lib_id "antmicroResistors0402:R_1k_0402")
		(at 160.02 48.26 90)
		(unit 1)
		(exclude_from_sim no)
		(in_bom yes)
		(on_board yes)
		(dnp no)
		(property "Reference" "R59"
			(at 161.29 44.45 90)
			(effects
				(font
					(size 1.27 1.27)
					(thickness 0.15)
				)
				(justify right)
			)
		)
		(property "Value" "R_1k_0402"
			(at 172.72 27.94 0)
			(effects
				(font
					(size 1.27 1.27)
					(thickness 0.15)
				)
				(justify left bottom)
				(hide yes)
			)
		)
		(property "Footprint" "antmicro-footprints:R_0402_1005Metric"
			(at 175.26 27.94 0)
			(effects
				(font
					(size 1.27 1.27)
					(thickness 0.15)
				)
				(justify left bottom)
				(hide yes)
			)
		)
		(property "Datasheet" "https://www.bourns.com/docs/product-datasheets/cr.pdf"
			(at 177.8 27.94 0)
			(effects
				(font
					(size 1.27 1.27)
					(thickness 0.15)
				)
				(justify left bottom)
				(hide yes)
			)
		)
		(property "Description" "SMD Chip Resistor, 1 kohm, ± 1%, 63 mW, 0402 [1005 Metric], Thick Film, General Purpose"
			(at 160.02 48.26 0)
			(effects
				(font
					(size 1.27 1.27)
				)
				(hide yes)
			)
		)
		(property "MPN" "CR0402-FX-1001GLF"
			(at 180.34 27.94 0)
			(effects
				(font
					(size 1.27 1.27)
					(thickness 0.15)
				)
				(justify left bottom)
				(hide yes)
			)
		)
		(property "Manufacturer" "Bourns"
			(at 182.88 27.94 0)
			(effects
				(font
					(size 1.27 1.27)
					(thickness 0.15)
				)
				(justify left bottom)
				(hide yes)
			)
		)
		(property "License" "Apache-2.0"
			(at 185.42 27.94 0)
			(effects
				(font
					(size 1.27 1.27)
					(thickness 0.15)
				)
				(justify left bottom)
				(hide yes)
			)
		)
		(property "Author" "Antmicro"
			(at 187.96 27.94 0)
			(effects
				(font
					(size 1.27 1.27)
					(thickness 0.15)
				)
				(justify left bottom)
				(hide yes)
			)
		)
		(property "Val" "1k"
			(at 161.29 46.99 90)
			(effects
				(font
					(size 1.27 1.27)
					(thickness 0.15)
				)
				(justify right)
			)
		)
		(property "Tolerance" "1%"
			(at 170.18 27.94 0)
			(effects
				(font
					(size 1.27 1.27)
				)
				(justify left bottom)
				(hide yes)
			)
		)
		(property "Public" ""
			(at 190.5 27.94 0)
			(effects
				(font
					(size 1.27 1.27)
				)
				(justify left bottom)
				(hide yes)
			)
		)
		(pin "2"
		)
		(pin "1"
		)
		(instances
			(project "polarfire-som"
				(path ""
					(reference "R59")
					(unit 1)
				)
			)
		)
	)
	(symbol
		(lib_id "antmicroCapacitors0402:C_100n_0402")
		(at 347.98 137.16 90)
		(unit 1)
		(exclude_from_sim no)
		(in_bom yes)
		(on_board yes)
		(dnp no)
		(property "Reference" "C220"
			(at 350.52 133.3435 90)
			(effects
				(font
					(size 1.27 1.27)
					(thickness 0.15)
				)
				(justify right)
			)
		)
		(property "Value" "C_100n_0402"
			(at 358.14 116.84 0)
			(effects
				(font
					(size 1.27 1.27)
					(thickness 0.15)
				)
				(justify left bottom)
				(hide yes)
			)
		)
		(property "Footprint" "antmicro-footprints:C_0402_1005Metric"
			(at 360.68 116.84 0)
			(effects
				(font
					(size 1.27 1.27)
					(thickness 0.15)
				)
				(justify left bottom)
				(hide yes)
			)
		)
		(property "Datasheet" "https://www.murata.com/products/productdetail?partno=GRM155R61H104KE14%23"
			(at 363.22 116.84 0)
			(effects
				(font
					(size 1.27 1.27)
					(thickness 0.15)
				)
				(justify left bottom)
				(hide yes)
			)
		)
		(property "Description" "SMD Multilayer Ceramic Capacitor, 0.1 µF, 50 V, 0402 [1005 Metric], ± 10%, X5R, GRM Series"
			(at 347.98 137.16 0)
			(effects
				(font
					(size 1.27 1.27)
				)
				(hide yes)
			)
		)
		(property "MPN" "GRM155R61H104KE14D"
			(at 365.76 116.84 0)
			(effects
				(font
					(size 1.27 1.27)
					(thickness 0.15)
				)
				(justify left bottom)
				(hide yes)
			)
		)
		(property "Manufacturer" "Murata"
			(at 368.3 116.84 0)
			(effects
				(font
					(size 1.27 1.27)
					(thickness 0.15)
				)
				(justify left bottom)
				(hide yes)
			)
		)
		(property "License" "Apache-2.0"
			(at 370.84 116.84 0)
			(effects
				(font
					(size 1.27 1.27)
					(thickness 0.15)
				)
				(justify left bottom)
				(hide yes)
			)
		)
		(property "Author" "Antmicro"
			(at 373.38 116.84 0)
			(effects
				(font
					(size 1.27 1.27)
					(thickness 0.15)
				)
				(justify left bottom)
				(hide yes)
			)
		)
		(property "Val" "100n"
			(at 355.6 135.255 90)
			(effects
				(font
					(size 1.27 1.27)
					(thickness 0.15)
				)
				(justify left bottom)
			)
		)
		(property "Voltage" "50V"
			(at 375.92 116.84 0)
			(effects
				(font
					(size 1.27 1.27)
				)
				(justify left bottom)
				(hide yes)
			)
		)
		(property "Dielectric" "X5R"
			(at 378.46 116.84 0)
			(effects
				(font
					(size 1.27 1.27)
				)
				(justify left bottom)
				(hide yes)
			)
		)
		(property "Public" ""
			(at 381 116.84 0)
			(effects
				(font
					(size 1.27 1.27)
				)
				(justify left bottom)
				(hide yes)
			)
		)
		(pin "1"
		)
		(pin "2"
		)
		(instances
			(project "polarfire-som"
				(path ""
					(reference "C220")
					(unit 1)
				)
			)
		)
	)
	(symbol
		(lib_id "antmicropower:+5V")
		(at 160.02 41.91 0)
		(mirror y)
		(unit 1)
		(exclude_from_sim no)
		(in_bom yes)
		(on_board yes)
		(dnp no)
		(property "Reference" "#PWR0204"
			(at 160.02 45.72 0)
			(effects
				(font
					(size 1.27 1.27)
				)
				(hide yes)
			)
		)
		(property "Value" "+5V"
			(at 160.02 38.1 0)
			(effects
				(font
					(size 1.27 1.27)
				)
			)
		)
		(property "Footprint" ""
			(at 160.02 41.91 0)
			(effects
				(font
					(size 1.27 1.27)
				)
				(hide yes)
			)
		)
		(property "Datasheet" ""
			(at 160.02 41.91 0)
			(effects
				(font
					(size 1.27 1.27)
				)
				(hide yes)
			)
		)
		(property "Description" ""
			(at 160.02 41.91 0)
			(effects
				(font
					(size 1.27 1.27)
				)
				(hide yes)
			)
		)
		(property "Author" "Antmicro"
			(at 144.78 49.53 0)
			(effects
				(font
					(size 1.27 1.27)
					(thickness 0.15)
				)
				(justify left bottom)
				(hide yes)
			)
		)
		(property "License" "Apache-2.0"
			(at 144.78 52.07 0)
			(effects
				(font
					(size 1.27 1.27)
					(thickness 0.15)
				)
				(justify left bottom)
				(hide yes)
			)
		)
		(pin "1"
		)
		(instances
			(project "polarfire-som"
				(path ""
					(reference "#PWR0204")
					(unit 1)
				)
			)
		)
	)
	(symbol
		(lib_id "antmicroCapacitors0402:C_1u_0402")
		(at 125.73 140.97 90)
		(unit 1)
		(exclude_from_sim no)
		(in_bom yes)
		(on_board yes)
		(dnp no)
		(property "Reference" "C180"
			(at 128.27 137.1535 90)
			(effects
				(font
					(size 1.27 1.27)
					(thickness 0.15)
				)
				(justify right)
			)
		)
		(property "Value" "C_1u_0402"
			(at 135.89 120.65 0)
			(effects
				(font
					(size 1.27 1.27)
					(thickness 0.15)
				)
				(justify left bottom)
				(hide yes)
			)
		)
		(property "Footprint" "antmicro-footprints:C_0402_1005Metric"
			(at 138.43 120.65 0)
			(effects
				(font
					(size 1.27 1.27)
					(thickness 0.15)
				)
				(justify left bottom)
				(hide yes)
			)
		)
		(property "Datasheet" "https://product.tdk.com/en/search/capacitor/ceramic/mlcc/info?part_no=C1005X6S1A105K050BC"
			(at 140.97 120.65 0)
			(effects
				(font
					(size 1.27 1.27)
					(thickness 0.15)
				)
				(justify left bottom)
				(hide yes)
			)
		)
		(property "Description" "SMD Multilayer Ceramic Capacitor, 1 µF, 10 V, 0402 [1005 Metric], ± 10%, X6S, C"
			(at 125.73 140.97 0)
			(effects
				(font
					(size 1.27 1.27)
				)
				(hide yes)
			)
		)
		(property "MPN" "C1005X6S1A105K050BC"
			(at 143.51 120.65 0)
			(effects
				(font
					(size 1.27 1.27)
					(thickness 0.15)
				)
				(justify left bottom)
				(hide yes)
			)
		)
		(property "Manufacturer" "TDK"
			(at 146.05 120.65 0)
			(effects
				(font
					(size 1.27 1.27)
					(thickness 0.15)
				)
				(justify left bottom)
				(hide yes)
			)
		)
		(property "License" "Apache-2.0"
			(at 148.59 120.65 0)
			(effects
				(font
					(size 1.27 1.27)
					(thickness 0.15)
				)
				(justify left bottom)
				(hide yes)
			)
		)
		(property "Author" "Antmicro"
			(at 151.13 120.65 0)
			(effects
				(font
					(size 1.27 1.27)
					(thickness 0.15)
				)
				(justify left bottom)
				(hide yes)
			)
		)
		(property "Val" "1u"
			(at 128.27 139.6935 90)
			(effects
				(font
					(size 1.27 1.27)
					(thickness 0.15)
				)
				(justify right)
			)
		)
		(property "Voltage" ""
			(at 153.67 120.65 0)
			(effects
				(font
					(size 1.27 1.27)
				)
				(justify left bottom)
				(hide yes)
			)
		)
		(property "Dielectric" ""
			(at 156.21 120.65 0)
			(effects
				(font
					(size 1.27 1.27)
				)
				(justify left bottom)
				(hide yes)
			)
		)
		(property "Public" ""
			(at 158.75 120.65 0)
			(effects
				(font
					(size 1.27 1.27)
				)
				(justify left bottom)
				(hide yes)
			)
		)
		(pin "1"
		)
		(pin "2"
		)
		(instances
			(project "polarfire-som"
				(path ""
					(reference "C180")
					(unit 1)
				)
			)
		)
	)
	(symbol
		(lib_id "antmicropower:GND")
		(at 74.93 196.85 0)
		(unit 1)
		(exclude_from_sim no)
		(in_bom yes)
		(on_board yes)
		(dnp no)
		(fields_autoplaced yes)
		(property "Reference" "#PWR0150"
			(at 83.82 199.39 0)
			(effects
				(font
					(size 1.27 1.27)
					(thickness 0.15)
				)
				(justify left bottom)
				(hide yes)
			)
		)
		(property "Value" "GND"
			(at 74.93 201.93 0)
			(effects
				(font
					(size 1.27 1.27)
					(thickness 0.15)
				)
			)
		)
		(property "Footprint" ""
			(at 83.82 204.47 0)
			(effects
				(font
					(size 1.27 1.27)
					(thickness 0.15)
				)
				(justify left bottom)
				(hide yes)
			)
		)
		(property "Datasheet" ""
			(at 83.82 209.55 0)
			(effects
				(font
					(size 1.27 1.27)
					(thickness 0.15)
				)
				(justify left bottom)
				(hide yes)
			)
		)
		(property "Description" ""
			(at 74.93 196.85 0)
			(effects
				(font
					(size 1.27 1.27)
				)
				(hide yes)
			)
		)
		(property "Author" "Antmicro"
			(at 83.82 204.47 0)
			(effects
				(font
					(size 1.27 1.27)
					(thickness 0.15)
				)
				(justify left bottom)
				(hide yes)
			)
		)
		(property "License" "Apache-2.0"
			(at 83.82 207.01 0)
			(effects
				(font
					(size 1.27 1.27)
					(thickness 0.15)
				)
				(justify left bottom)
				(hide yes)
			)
		)
		(pin "1"
		)
		(instances
			(project "polarfire-som"
				(path ""
					(reference "#PWR0150")
					(unit 1)
				)
			)
		)
	)
)
